G04 ================== begin FILE IDENTIFICATION RECORD ==================*
G04 Layout Name:  12433-2a.brd*
G04 Film Name:    NOTICE*
G04 File Format:  Gerber RS274X*
G04 File Origin:  Cadence Allegro 16.5-S056*
G04 Origin Date:  Fri Dec 11 16:47:37 2015*
G04 *
G04 Layer:  MANUFACTURING/THERMAL*
G04 *
G04 Offset:    (0.00 0.00)*
G04 Mirror:    No*
G04 Mode:      Positive*
G04 Rotation:  0*
G04 FullContactRelief:  No*
G04 UndefLineWidth:     6.00*
G04 ================== end FILE IDENTIFICATION RECORD ====================*
%FSLAX35Y35*MOIN*%
%IR0*IPPOS*OFA0.00000B0.00000*MIA0B0*SFA1.00000B1.00000*%
%ADD10C,.02*%
%ADD11C,.015*%
%ADD12C,.006*%
G75*
%LPD*%
G75*
G36*
G01X-116382Y1260682D02*
G02X-137928Y1282228I7501J29047D01*
G01X-143068Y1282229D01*
G03X-116381Y1255542I34187J7500D01*
G01X-116382Y1260682D01*
G37*
G36*
G01X-137928Y1297229D02*
G02X-116382Y1318776I29047J-7500D01*
G01X-116381Y1323916D01*
G03X-143068Y1297228I7500J-34187D01*
G01X-137928Y1297229D01*
G37*
G36*
G01X-61511Y810610D02*
G02X-89070Y848167I11812J37557D01*
G01Y863915D01*
X-83165D01*
Y848167D01*
G03X-61511Y816856I33464J0D01*
G01Y810610D01*
G37*
G36*
G01X-89070Y903285D02*
Y919033D01*
G02X-61511Y956590I39371J0D01*
G01Y950344D01*
G03X-83165Y919033I11810J-31311D01*
G01Y903285D01*
X-89070D01*
G37*
G36*
G01X-79834Y1282228D02*
G02X-101381Y1260682I-29047J7501D01*
G01X-101382Y1255542D01*
G03X-74694Y1282229I-7499J34187D01*
G01X-79834Y1282228D01*
G37*
G36*
G01X-101381Y1318776D02*
G02X-79834Y1297229I-7500J-29047D01*
G01X-74694Y1297228D01*
G03X-101382Y1323916I-34187J-7499D01*
G01X-101381Y1318776D01*
G37*
G36*
G01X-37889Y810610D02*
Y816856D01*
G03X-16235Y848167I-11810J31311D01*
G01Y863915D01*
X-10330D01*
Y848167D01*
G02X-37889Y810610I-39371J0D01*
G37*
G36*
G01X-16235Y903285D02*
Y919033D01*
G03X-37889Y950344I-33464J0D01*
G01Y956590D01*
G02X-10330Y919033I-11812J-37557D01*
G01Y903285D01*
X-16235D01*
G37*
G54D10*
G01X-284108Y651800D02*
Y664300D01*
X-276192D01*
G01X-279108Y658258D02*
X-284108D01*
G01X-264650Y651800D02*
X-265900Y652008D01*
X-267150Y652841D01*
X-267984Y654300D01*
X-268400Y655967D01*
X-267984Y657633D01*
X-267150Y659092D01*
X-265900Y659925D01*
X-264650Y660133D01*
X-263400Y659925D01*
X-262150Y659092D01*
X-261317Y657633D01*
X-261108Y655967D01*
X-261317Y654300D01*
X-262150Y652841D01*
X-263400Y652008D01*
X-264650Y651800D01*
G01X-252067D02*
Y660133D01*
G01Y658467D02*
X-251025Y659300D01*
X-249983Y659925D01*
X-248525Y660133D01*
X-247483Y659925D01*
X-246233Y659300D01*
G01X-222108Y662217D02*
X-220858Y663466D01*
X-219400Y664092D01*
X-217733Y664300D01*
X-215650Y663883D01*
X-214192Y662842D01*
X-213775Y661592D01*
X-213983Y660341D01*
X-214817Y659300D01*
X-218983Y657217D01*
X-220858Y655758D01*
X-222108Y653675D01*
X-222525Y651800D01*
X-213775D01*
G01X-203067D02*
X-202650Y654508D01*
X-202025Y656800D01*
X-201192Y658883D01*
X-200150Y661175D01*
X-198483Y664300D01*
X-206817D01*
G01X-184650Y651800D02*
Y664300D01*
X-192359Y655342D01*
X-181941D01*
G01X-176025Y651800D02*
X-167275Y664300D01*
G01X-176025D02*
X-167275Y651800D01*
G01X-143567Y648675D02*
X-142108Y647842D01*
X-140442Y647633D01*
X-138983Y647842D01*
X-137733Y648883D01*
X-136900Y650342D01*
Y660133D01*
G01Y658467D02*
X-137733Y659300D01*
X-138983Y659925D01*
X-140442Y660133D01*
X-142108Y659717D01*
X-143150Y658883D01*
X-143984Y657425D01*
X-144400Y655967D01*
X-144192Y654716D01*
X-143358Y653258D01*
X-142108Y652217D01*
X-140442Y651800D01*
X-139192Y652008D01*
X-137733Y652841D01*
X-136900Y653675D01*
G01X-128275Y657425D02*
X-121608D01*
X-122233Y658883D01*
X-123275Y659717D01*
X-124733Y660133D01*
X-126192Y659925D01*
X-127442Y659300D01*
X-128275Y657842D01*
X-128692Y656591D01*
Y655342D01*
X-128275Y654092D01*
X-127233Y652841D01*
X-125983Y652008D01*
X-124525Y651800D01*
X-123067Y652217D01*
X-121608Y653466D01*
G01X-112567Y651800D02*
Y660133D01*
G01Y658467D02*
X-111525Y659300D01*
X-110483Y659925D01*
X-109025Y660133D01*
X-107983Y659925D01*
X-106733Y659300D01*
G01X-97900Y651800D02*
Y664300D01*
G01Y658050D02*
X-96858Y659300D01*
X-95608Y659925D01*
X-94358Y660133D01*
X-92483Y659717D01*
X-91233Y658883D01*
X-90400Y657425D01*
Y655758D01*
X-90817Y654092D01*
X-91650Y652841D01*
X-93108Y652008D01*
X-94358Y651800D01*
X-95608Y652008D01*
X-96858Y652633D01*
X-97900Y653675D01*
G01X-81775Y657425D02*
X-75108D01*
X-75733Y658883D01*
X-76775Y659717D01*
X-78233Y660133D01*
X-79692Y659925D01*
X-80942Y659300D01*
X-81775Y657842D01*
X-82192Y656591D01*
Y655342D01*
X-81775Y654092D01*
X-80733Y652841D01*
X-79483Y652008D01*
X-78025Y651800D01*
X-76567Y652217D01*
X-75108Y653466D01*
G01X-66067Y651800D02*
Y660133D01*
G01Y658467D02*
X-65025Y659300D01*
X-63983Y659925D01*
X-62525Y660133D01*
X-61483Y659925D01*
X-60233Y659300D01*
G01X-33400Y651800D02*
Y662425D01*
X-32983Y663466D01*
X-32150Y664092D01*
X-30900Y664300D01*
X-29650Y663883D01*
X-29025Y662842D01*
G01X-31525Y659300D02*
X-35692D01*
G01X-16650Y651800D02*
X-17900Y652008D01*
X-19150Y652841D01*
X-19984Y654300D01*
X-20400Y655967D01*
X-19984Y657633D01*
X-19150Y659092D01*
X-17900Y659925D01*
X-16650Y660133D01*
X-15400Y659925D01*
X-14150Y659092D01*
X-13317Y657633D01*
X-13108Y655967D01*
X-13317Y654300D01*
X-14150Y652841D01*
X-15400Y652008D01*
X-16650Y651800D01*
G01X-4067D02*
Y660133D01*
G01Y658467D02*
X-3025Y659300D01*
X-1983Y659925D01*
X-525Y660133D01*
X517Y659925D01*
X1767Y659300D01*
G01X8100Y651800D02*
Y660133D01*
G01Y657842D02*
X8725Y658883D01*
X9767Y659717D01*
X11225Y660133D01*
X12683Y659717D01*
X13725Y658883D01*
X14350Y657842D01*
Y651800D01*
G01Y657842D02*
X14975Y658883D01*
X16017Y659717D01*
X17475Y660133D01*
X18933Y659717D01*
X19975Y658883D01*
X20600Y657633D01*
Y651800D01*
G01X33600D02*
Y660133D01*
G01Y658675D02*
X32767Y659508D01*
X31517Y659925D01*
X30058Y660133D01*
X28600Y659717D01*
X27350Y658883D01*
X26516Y657633D01*
X26100Y655967D01*
X26516Y654300D01*
X27350Y653050D01*
X28600Y652217D01*
X30058Y651800D01*
X31517Y652008D01*
X32767Y652633D01*
X33600Y653466D01*
G01X45350Y664300D02*
Y651800D01*
G01X42433Y660133D02*
X48267D01*
G01X76350Y664300D02*
Y651800D01*
G01X73433Y660133D02*
X79267D01*
G01X88308Y651800D02*
Y664300D01*
G01Y658258D02*
X89350Y659300D01*
X90392Y659925D01*
X92058Y660133D01*
X93308Y659925D01*
X94767Y659092D01*
X95392Y657842D01*
Y651800D01*
G01X104225Y657425D02*
X110892D01*
X110267Y658883D01*
X109225Y659717D01*
X107767Y660133D01*
X106308Y659925D01*
X105058Y659300D01*
X104225Y657842D01*
X103808Y656591D01*
Y655342D01*
X104225Y654092D01*
X105267Y652841D01*
X106517Y652008D01*
X107975Y651800D01*
X109433Y652217D01*
X110892Y653466D01*
G01X119933Y651800D02*
Y660133D01*
G01Y658467D02*
X120975Y659300D01*
X122017Y659925D01*
X123475Y660133D01*
X124517Y659925D01*
X125767Y659300D01*
G01X132100Y651800D02*
Y660133D01*
G01Y657842D02*
X132725Y658883D01*
X133767Y659717D01*
X135225Y660133D01*
X136683Y659717D01*
X137725Y658883D01*
X138350Y657842D01*
Y651800D01*
G01Y657842D02*
X138975Y658883D01*
X140017Y659717D01*
X141475Y660133D01*
X142933Y659717D01*
X143975Y658883D01*
X144600Y657633D01*
Y651800D01*
G01X157600D02*
Y660133D01*
G01Y658675D02*
X156767Y659508D01*
X155517Y659925D01*
X154058Y660133D01*
X152600Y659717D01*
X151350Y658883D01*
X150516Y657633D01*
X150100Y655967D01*
X150516Y654300D01*
X151350Y653050D01*
X152600Y652217D01*
X154058Y651800D01*
X155517Y652008D01*
X156767Y652633D01*
X157600Y653466D01*
G01X169350Y651800D02*
Y664300D01*
G01X197433Y651800D02*
Y660133D01*
G01Y658467D02*
X198475Y659300D01*
X199517Y659925D01*
X200975Y660133D01*
X202017Y659925D01*
X203267Y659300D01*
G01X212725Y657425D02*
X219392D01*
X218767Y658883D01*
X217725Y659717D01*
X216267Y660133D01*
X214808Y659925D01*
X213558Y659300D01*
X212725Y657842D01*
X212308Y656591D01*
Y655342D01*
X212725Y654092D01*
X213767Y652841D01*
X215017Y652008D01*
X216475Y651800D01*
X217933Y652217D01*
X219392Y653466D01*
G01X231350Y651800D02*
Y664300D01*
G01X246850Y660133D02*
Y651800D01*
G01Y663466D02*
X246433Y663675D01*
Y664092D01*
X246850Y664300D01*
X247267Y664092D01*
Y663675D01*
X246850Y663466D01*
G01X259225Y657425D02*
X265892D01*
X265267Y658883D01*
X264225Y659717D01*
X262767Y660133D01*
X261308Y659925D01*
X260058Y659300D01*
X259225Y657842D01*
X258808Y656591D01*
Y655342D01*
X259225Y654092D01*
X260267Y652841D01*
X261517Y652008D01*
X262975Y651800D01*
X264433Y652217D01*
X265892Y653466D01*
G01X276600Y651800D02*
Y662425D01*
X277017Y663466D01*
X277850Y664092D01*
X279100Y664300D01*
X280350Y663883D01*
X280975Y662842D01*
G01X278475Y659300D02*
X274308D01*
G01X-281400Y630100D02*
Y640725D01*
X-280983Y641766D01*
X-280150Y642392D01*
X-278900Y642600D01*
X-277650Y642183D01*
X-277025Y641142D01*
G01X-279525Y637600D02*
X-283692D01*
G01X-264650Y630100D02*
X-265900Y630308D01*
X-267150Y631141D01*
X-267984Y632600D01*
X-268400Y634267D01*
X-267984Y635933D01*
X-267150Y637392D01*
X-265900Y638225D01*
X-264650Y638433D01*
X-263400Y638225D01*
X-262150Y637392D01*
X-261317Y635933D01*
X-261108Y634267D01*
X-261317Y632600D01*
X-262150Y631141D01*
X-263400Y630308D01*
X-264650Y630100D01*
G01X-249150D02*
Y642600D01*
G01X-233650Y630100D02*
Y642600D01*
G01X-218150Y630100D02*
X-219400Y630308D01*
X-220650Y631141D01*
X-221484Y632600D01*
X-221900Y634267D01*
X-221484Y635933D01*
X-220650Y637392D01*
X-219400Y638225D01*
X-218150Y638433D01*
X-216900Y638225D01*
X-215650Y637392D01*
X-214817Y635933D01*
X-214608Y634267D01*
X-214817Y632600D01*
X-215650Y631141D01*
X-216900Y630308D01*
X-218150Y630100D01*
G01X-207859Y638433D02*
X-205358Y630100D01*
X-202650Y638433D01*
X-199942Y630100D01*
X-197441Y638433D01*
G01X-174567Y626975D02*
X-173108Y626142D01*
X-171442Y625933D01*
X-169983Y626142D01*
X-168733Y627183D01*
X-167900Y628642D01*
Y638433D01*
G01Y636767D02*
X-168733Y637600D01*
X-169983Y638225D01*
X-171442Y638433D01*
X-173108Y638017D01*
X-174150Y637183D01*
X-174984Y635725D01*
X-175400Y634267D01*
X-175192Y633016D01*
X-174358Y631558D01*
X-173108Y630517D01*
X-171442Y630100D01*
X-170192Y630308D01*
X-168733Y631141D01*
X-167900Y631975D01*
G01X-159275Y635725D02*
X-152608D01*
X-153233Y637183D01*
X-154275Y638017D01*
X-155733Y638433D01*
X-157192Y638225D01*
X-158442Y637600D01*
X-159275Y636142D01*
X-159692Y634891D01*
Y633642D01*
X-159275Y632392D01*
X-158233Y631141D01*
X-156983Y630308D01*
X-155525Y630100D01*
X-154067Y630517D01*
X-152608Y631766D01*
G01X-143567Y630100D02*
Y638433D01*
G01Y636767D02*
X-142525Y637600D01*
X-141483Y638225D01*
X-140025Y638433D01*
X-138983Y638225D01*
X-137733Y637600D01*
G01X-128900Y630100D02*
Y642600D01*
G01Y636350D02*
X-127858Y637600D01*
X-126608Y638225D01*
X-125358Y638433D01*
X-123483Y638017D01*
X-122233Y637183D01*
X-121400Y635725D01*
Y634058D01*
X-121817Y632392D01*
X-122650Y631141D01*
X-124108Y630308D01*
X-125358Y630100D01*
X-126608Y630308D01*
X-127858Y630933D01*
X-128900Y631975D01*
G01X-112775Y635725D02*
X-106108D01*
X-106733Y637183D01*
X-107775Y638017D01*
X-109233Y638433D01*
X-110692Y638225D01*
X-111942Y637600D01*
X-112775Y636142D01*
X-113192Y634891D01*
Y633642D01*
X-112775Y632392D01*
X-111733Y631141D01*
X-110483Y630308D01*
X-109025Y630100D01*
X-107567Y630517D01*
X-106108Y631766D01*
G01X-97067Y630100D02*
Y638433D01*
G01Y636767D02*
X-96025Y637600D01*
X-94983Y638225D01*
X-93525Y638433D01*
X-92483Y638225D01*
X-91233Y637600D01*
G01X-59400Y642600D02*
Y630100D01*
G01Y631975D02*
X-60233Y630933D01*
X-61483Y630308D01*
X-62942Y630100D01*
X-64608Y630517D01*
X-65858Y631558D01*
X-66692Y632808D01*
X-66900Y634267D01*
X-66692Y635725D01*
X-65858Y636975D01*
X-64608Y638017D01*
X-62942Y638433D01*
X-61483Y638225D01*
X-60442Y637808D01*
X-59400Y636975D01*
G01X-50775Y635725D02*
X-44108D01*
X-44733Y637183D01*
X-45775Y638017D01*
X-47233Y638433D01*
X-48692Y638225D01*
X-49942Y637600D01*
X-50775Y636142D01*
X-51192Y634891D01*
Y633642D01*
X-50775Y632392D01*
X-49733Y631141D01*
X-48483Y630308D01*
X-47025Y630100D01*
X-45567Y630517D01*
X-44108Y631766D01*
G01X-35275Y631558D02*
X-34233Y630725D01*
X-32775Y630100D01*
X-31525D01*
X-30275Y630517D01*
X-29442Y631141D01*
X-29025Y631975D01*
X-29233Y633225D01*
X-30067Y633850D01*
X-33817Y635100D01*
X-34650Y636558D01*
X-34233Y637600D01*
X-33400Y638225D01*
X-32150Y638433D01*
X-30900Y638225D01*
X-29650Y637600D01*
G01X-16650Y638433D02*
Y630100D01*
G01Y641766D02*
X-17067Y641975D01*
Y642392D01*
X-16650Y642600D01*
X-16233Y642392D01*
Y641975D01*
X-16650Y641766D01*
G01X-4067Y626975D02*
X-2608Y626142D01*
X-942Y625933D01*
X517Y626142D01*
X1767Y627183D01*
X2600Y628642D01*
Y638433D01*
G01Y636767D02*
X1767Y637600D01*
X517Y638225D01*
X-942Y638433D01*
X-2608Y638017D01*
X-3650Y637183D01*
X-4484Y635725D01*
X-4900Y634267D01*
X-4692Y633016D01*
X-3858Y631558D01*
X-2608Y630517D01*
X-942Y630100D01*
X308Y630308D01*
X1767Y631141D01*
X2600Y631975D01*
G01X10808Y630100D02*
Y638433D01*
G01Y636350D02*
X11642Y637392D01*
X12892Y638225D01*
X14558Y638433D01*
X16017Y638225D01*
X17267Y637392D01*
X17892Y635933D01*
Y630100D01*
G01X-274508Y1105700D02*
Y1118200D01*
X-266592D01*
G01X-269508Y1112158D02*
X-274508D01*
G01X-255050Y1105700D02*
X-256300Y1105908D01*
X-257550Y1106741D01*
X-258384Y1108200D01*
X-258800Y1109867D01*
X-258384Y1111533D01*
X-257550Y1112992D01*
X-256300Y1113825D01*
X-255050Y1114033D01*
X-253800Y1113825D01*
X-252550Y1112992D01*
X-251717Y1111533D01*
X-251508Y1109867D01*
X-251717Y1108200D01*
X-252550Y1106741D01*
X-253800Y1105908D01*
X-255050Y1105700D01*
G01X-242467D02*
Y1114033D01*
G01Y1112367D02*
X-241425Y1113200D01*
X-240383Y1113825D01*
X-238925Y1114033D01*
X-237883Y1113825D01*
X-236633Y1113200D01*
G01X-212508Y1116117D02*
X-211258Y1117366D01*
X-209800Y1117992D01*
X-208133Y1118200D01*
X-206050Y1117783D01*
X-204592Y1116742D01*
X-204175Y1115492D01*
X-204383Y1114241D01*
X-205217Y1113200D01*
X-209383Y1111117D01*
X-211258Y1109658D01*
X-212508Y1107575D01*
X-212925Y1105700D01*
X-204175D01*
G01X-193467D02*
X-193050Y1108408D01*
X-192425Y1110700D01*
X-191592Y1112783D01*
X-190550Y1115075D01*
X-188883Y1118200D01*
X-197217D01*
G01X-175050Y1105700D02*
Y1118200D01*
X-182759Y1109242D01*
X-172341D01*
G01X-166425Y1105700D02*
X-157675Y1118200D01*
G01X-166425D02*
X-157675Y1105700D01*
G01X-133967Y1102575D02*
X-132508Y1101742D01*
X-130842Y1101533D01*
X-129383Y1101742D01*
X-128133Y1102783D01*
X-127300Y1104242D01*
Y1114033D01*
G01Y1112367D02*
X-128133Y1113200D01*
X-129383Y1113825D01*
X-130842Y1114033D01*
X-132508Y1113617D01*
X-133550Y1112783D01*
X-134384Y1111325D01*
X-134800Y1109867D01*
X-134592Y1108616D01*
X-133758Y1107158D01*
X-132508Y1106117D01*
X-130842Y1105700D01*
X-129592Y1105908D01*
X-128133Y1106741D01*
X-127300Y1107575D01*
G01X-118675Y1111325D02*
X-112008D01*
X-112633Y1112783D01*
X-113675Y1113617D01*
X-115133Y1114033D01*
X-116592Y1113825D01*
X-117842Y1113200D01*
X-118675Y1111742D01*
X-119092Y1110491D01*
Y1109242D01*
X-118675Y1107992D01*
X-117633Y1106741D01*
X-116383Y1105908D01*
X-114925Y1105700D01*
X-113467Y1106117D01*
X-112008Y1107366D01*
G01X-102967Y1105700D02*
Y1114033D01*
G01Y1112367D02*
X-101925Y1113200D01*
X-100883Y1113825D01*
X-99425Y1114033D01*
X-98383Y1113825D01*
X-97133Y1113200D01*
G01X-88300Y1105700D02*
Y1118200D01*
G01Y1111950D02*
X-87258Y1113200D01*
X-86008Y1113825D01*
X-84758Y1114033D01*
X-82883Y1113617D01*
X-81633Y1112783D01*
X-80800Y1111325D01*
Y1109658D01*
X-81217Y1107992D01*
X-82050Y1106741D01*
X-83508Y1105908D01*
X-84758Y1105700D01*
X-86008Y1105908D01*
X-87258Y1106533D01*
X-88300Y1107575D01*
G01X-72175Y1111325D02*
X-65508D01*
X-66133Y1112783D01*
X-67175Y1113617D01*
X-68633Y1114033D01*
X-70092Y1113825D01*
X-71342Y1113200D01*
X-72175Y1111742D01*
X-72592Y1110491D01*
Y1109242D01*
X-72175Y1107992D01*
X-71133Y1106741D01*
X-69883Y1105908D01*
X-68425Y1105700D01*
X-66967Y1106117D01*
X-65508Y1107366D01*
G01X-56467Y1105700D02*
Y1114033D01*
G01Y1112367D02*
X-55425Y1113200D01*
X-54383Y1113825D01*
X-52925Y1114033D01*
X-51883Y1113825D01*
X-50633Y1113200D01*
G01X-23800Y1105700D02*
Y1116325D01*
X-23383Y1117366D01*
X-22550Y1117992D01*
X-21300Y1118200D01*
X-20050Y1117783D01*
X-19425Y1116742D01*
G01X-21925Y1113200D02*
X-26092D01*
G01X-7050Y1105700D02*
X-8300Y1105908D01*
X-9550Y1106741D01*
X-10384Y1108200D01*
X-10800Y1109867D01*
X-10384Y1111533D01*
X-9550Y1112992D01*
X-8300Y1113825D01*
X-7050Y1114033D01*
X-5800Y1113825D01*
X-4550Y1112992D01*
X-3717Y1111533D01*
X-3508Y1109867D01*
X-3717Y1108200D01*
X-4550Y1106741D01*
X-5800Y1105908D01*
X-7050Y1105700D01*
G01X5533D02*
Y1114033D01*
G01Y1112367D02*
X6575Y1113200D01*
X7617Y1113825D01*
X9075Y1114033D01*
X10117Y1113825D01*
X11367Y1113200D01*
G01X17700Y1105700D02*
Y1114033D01*
G01Y1111742D02*
X18325Y1112783D01*
X19367Y1113617D01*
X20825Y1114033D01*
X22283Y1113617D01*
X23325Y1112783D01*
X23950Y1111742D01*
Y1105700D01*
G01Y1111742D02*
X24575Y1112783D01*
X25617Y1113617D01*
X27075Y1114033D01*
X28533Y1113617D01*
X29575Y1112783D01*
X30200Y1111533D01*
Y1105700D01*
G01X43200D02*
Y1114033D01*
G01Y1112575D02*
X42367Y1113408D01*
X41117Y1113825D01*
X39658Y1114033D01*
X38200Y1113617D01*
X36950Y1112783D01*
X36116Y1111533D01*
X35700Y1109867D01*
X36116Y1108200D01*
X36950Y1106950D01*
X38200Y1106117D01*
X39658Y1105700D01*
X41117Y1105908D01*
X42367Y1106533D01*
X43200Y1107366D01*
G01X54950Y1118200D02*
Y1105700D01*
G01X52033Y1114033D02*
X57867D01*
G01X85950Y1118200D02*
Y1105700D01*
G01X83033Y1114033D02*
X88867D01*
G01X97908Y1105700D02*
Y1118200D01*
G01Y1112158D02*
X98950Y1113200D01*
X99992Y1113825D01*
X101658Y1114033D01*
X102908Y1113825D01*
X104367Y1112992D01*
X104992Y1111742D01*
Y1105700D01*
G01X113825Y1111325D02*
X120492D01*
X119867Y1112783D01*
X118825Y1113617D01*
X117367Y1114033D01*
X115908Y1113825D01*
X114658Y1113200D01*
X113825Y1111742D01*
X113408Y1110491D01*
Y1109242D01*
X113825Y1107992D01*
X114867Y1106741D01*
X116117Y1105908D01*
X117575Y1105700D01*
X119033Y1106117D01*
X120492Y1107366D01*
G01X129533Y1105700D02*
Y1114033D01*
G01Y1112367D02*
X130575Y1113200D01*
X131617Y1113825D01*
X133075Y1114033D01*
X134117Y1113825D01*
X135367Y1113200D01*
G01X141700Y1105700D02*
Y1114033D01*
G01Y1111742D02*
X142325Y1112783D01*
X143367Y1113617D01*
X144825Y1114033D01*
X146283Y1113617D01*
X147325Y1112783D01*
X147950Y1111742D01*
Y1105700D01*
G01Y1111742D02*
X148575Y1112783D01*
X149617Y1113617D01*
X151075Y1114033D01*
X152533Y1113617D01*
X153575Y1112783D01*
X154200Y1111533D01*
Y1105700D01*
G01X167200D02*
Y1114033D01*
G01Y1112575D02*
X166367Y1113408D01*
X165117Y1113825D01*
X163658Y1114033D01*
X162200Y1113617D01*
X160950Y1112783D01*
X160116Y1111533D01*
X159700Y1109867D01*
X160116Y1108200D01*
X160950Y1106950D01*
X162200Y1106117D01*
X163658Y1105700D01*
X165117Y1105908D01*
X166367Y1106533D01*
X167200Y1107366D01*
G01X178950Y1105700D02*
Y1118200D01*
G01X207033Y1105700D02*
Y1114033D01*
G01Y1112367D02*
X208075Y1113200D01*
X209117Y1113825D01*
X210575Y1114033D01*
X211617Y1113825D01*
X212867Y1113200D01*
G01X222325Y1111325D02*
X228992D01*
X228367Y1112783D01*
X227325Y1113617D01*
X225867Y1114033D01*
X224408Y1113825D01*
X223158Y1113200D01*
X222325Y1111742D01*
X221908Y1110491D01*
Y1109242D01*
X222325Y1107992D01*
X223367Y1106741D01*
X224617Y1105908D01*
X226075Y1105700D01*
X227533Y1106117D01*
X228992Y1107366D01*
G01X240950Y1105700D02*
Y1118200D01*
G01X256450Y1114033D02*
Y1105700D01*
G01Y1117366D02*
X256033Y1117575D01*
Y1117992D01*
X256450Y1118200D01*
X256867Y1117992D01*
Y1117575D01*
X256450Y1117366D01*
G01X268825Y1111325D02*
X275492D01*
X274867Y1112783D01*
X273825Y1113617D01*
X272367Y1114033D01*
X270908Y1113825D01*
X269658Y1113200D01*
X268825Y1111742D01*
X268408Y1110491D01*
Y1109242D01*
X268825Y1107992D01*
X269867Y1106741D01*
X271117Y1105908D01*
X272575Y1105700D01*
X274033Y1106117D01*
X275492Y1107366D01*
G01X286200Y1105700D02*
Y1116325D01*
X286617Y1117366D01*
X287450Y1117992D01*
X288700Y1118200D01*
X289950Y1117783D01*
X290575Y1116742D01*
G01X288075Y1113200D02*
X283908D01*
G01X-271800Y1084000D02*
Y1094625D01*
X-271383Y1095666D01*
X-270550Y1096292D01*
X-269300Y1096500D01*
X-268050Y1096083D01*
X-267425Y1095042D01*
G01X-269925Y1091500D02*
X-274092D01*
G01X-255050Y1084000D02*
X-256300Y1084208D01*
X-257550Y1085041D01*
X-258384Y1086500D01*
X-258800Y1088167D01*
X-258384Y1089833D01*
X-257550Y1091292D01*
X-256300Y1092125D01*
X-255050Y1092333D01*
X-253800Y1092125D01*
X-252550Y1091292D01*
X-251717Y1089833D01*
X-251508Y1088167D01*
X-251717Y1086500D01*
X-252550Y1085041D01*
X-253800Y1084208D01*
X-255050Y1084000D01*
G01X-239550D02*
Y1096500D01*
G01X-224050Y1084000D02*
Y1096500D01*
G01X-208550Y1084000D02*
X-209800Y1084208D01*
X-211050Y1085041D01*
X-211884Y1086500D01*
X-212300Y1088167D01*
X-211884Y1089833D01*
X-211050Y1091292D01*
X-209800Y1092125D01*
X-208550Y1092333D01*
X-207300Y1092125D01*
X-206050Y1091292D01*
X-205217Y1089833D01*
X-205008Y1088167D01*
X-205217Y1086500D01*
X-206050Y1085041D01*
X-207300Y1084208D01*
X-208550Y1084000D01*
G01X-198259Y1092333D02*
X-195758Y1084000D01*
X-193050Y1092333D01*
X-190342Y1084000D01*
X-187841Y1092333D01*
G01X-164967Y1080875D02*
X-163508Y1080042D01*
X-161842Y1079833D01*
X-160383Y1080042D01*
X-159133Y1081083D01*
X-158300Y1082542D01*
Y1092333D01*
G01Y1090667D02*
X-159133Y1091500D01*
X-160383Y1092125D01*
X-161842Y1092333D01*
X-163508Y1091917D01*
X-164550Y1091083D01*
X-165384Y1089625D01*
X-165800Y1088167D01*
X-165592Y1086916D01*
X-164758Y1085458D01*
X-163508Y1084417D01*
X-161842Y1084000D01*
X-160592Y1084208D01*
X-159133Y1085041D01*
X-158300Y1085875D01*
G01X-149675Y1089625D02*
X-143008D01*
X-143633Y1091083D01*
X-144675Y1091917D01*
X-146133Y1092333D01*
X-147592Y1092125D01*
X-148842Y1091500D01*
X-149675Y1090042D01*
X-150092Y1088791D01*
Y1087542D01*
X-149675Y1086292D01*
X-148633Y1085041D01*
X-147383Y1084208D01*
X-145925Y1084000D01*
X-144467Y1084417D01*
X-143008Y1085666D01*
G01X-133967Y1084000D02*
Y1092333D01*
G01Y1090667D02*
X-132925Y1091500D01*
X-131883Y1092125D01*
X-130425Y1092333D01*
X-129383Y1092125D01*
X-128133Y1091500D01*
G01X-119300Y1084000D02*
Y1096500D01*
G01Y1090250D02*
X-118258Y1091500D01*
X-117008Y1092125D01*
X-115758Y1092333D01*
X-113883Y1091917D01*
X-112633Y1091083D01*
X-111800Y1089625D01*
Y1087958D01*
X-112217Y1086292D01*
X-113050Y1085041D01*
X-114508Y1084208D01*
X-115758Y1084000D01*
X-117008Y1084208D01*
X-118258Y1084833D01*
X-119300Y1085875D01*
G01X-103175Y1089625D02*
X-96508D01*
X-97133Y1091083D01*
X-98175Y1091917D01*
X-99633Y1092333D01*
X-101092Y1092125D01*
X-102342Y1091500D01*
X-103175Y1090042D01*
X-103592Y1088791D01*
Y1087542D01*
X-103175Y1086292D01*
X-102133Y1085041D01*
X-100883Y1084208D01*
X-99425Y1084000D01*
X-97967Y1084417D01*
X-96508Y1085666D01*
G01X-87467Y1084000D02*
Y1092333D01*
G01Y1090667D02*
X-86425Y1091500D01*
X-85383Y1092125D01*
X-83925Y1092333D01*
X-82883Y1092125D01*
X-81633Y1091500D01*
G01X-49800Y1096500D02*
Y1084000D01*
G01Y1085875D02*
X-50633Y1084833D01*
X-51883Y1084208D01*
X-53342Y1084000D01*
X-55008Y1084417D01*
X-56258Y1085458D01*
X-57092Y1086708D01*
X-57300Y1088167D01*
X-57092Y1089625D01*
X-56258Y1090875D01*
X-55008Y1091917D01*
X-53342Y1092333D01*
X-51883Y1092125D01*
X-50842Y1091708D01*
X-49800Y1090875D01*
G01X-41175Y1089625D02*
X-34508D01*
X-35133Y1091083D01*
X-36175Y1091917D01*
X-37633Y1092333D01*
X-39092Y1092125D01*
X-40342Y1091500D01*
X-41175Y1090042D01*
X-41592Y1088791D01*
Y1087542D01*
X-41175Y1086292D01*
X-40133Y1085041D01*
X-38883Y1084208D01*
X-37425Y1084000D01*
X-35967Y1084417D01*
X-34508Y1085666D01*
G01X-25675Y1085458D02*
X-24633Y1084625D01*
X-23175Y1084000D01*
X-21925D01*
X-20675Y1084417D01*
X-19842Y1085041D01*
X-19425Y1085875D01*
X-19633Y1087125D01*
X-20467Y1087750D01*
X-24217Y1089000D01*
X-25050Y1090458D01*
X-24633Y1091500D01*
X-23800Y1092125D01*
X-22550Y1092333D01*
X-21300Y1092125D01*
X-20050Y1091500D01*
G01X-7050Y1092333D02*
Y1084000D01*
G01Y1095666D02*
X-7467Y1095875D01*
Y1096292D01*
X-7050Y1096500D01*
X-6633Y1096292D01*
Y1095875D01*
X-7050Y1095666D01*
G01X5533Y1080875D02*
X6992Y1080042D01*
X8658Y1079833D01*
X10117Y1080042D01*
X11367Y1081083D01*
X12200Y1082542D01*
Y1092333D01*
G01Y1090667D02*
X11367Y1091500D01*
X10117Y1092125D01*
X8658Y1092333D01*
X6992Y1091917D01*
X5950Y1091083D01*
X5116Y1089625D01*
X4700Y1088167D01*
X4908Y1086916D01*
X5742Y1085458D01*
X6992Y1084417D01*
X8658Y1084000D01*
X9908Y1084208D01*
X11367Y1085041D01*
X12200Y1085875D01*
G01X20408Y1084000D02*
Y1092333D01*
G01Y1090250D02*
X21242Y1091292D01*
X22492Y1092125D01*
X24158Y1092333D01*
X25617Y1092125D01*
X26867Y1091292D01*
X27492Y1089833D01*
Y1084000D01*
G01X-204633Y1405600D02*
Y1418100D01*
X-200467D01*
X-198800Y1417475D01*
X-197550Y1416642D01*
X-196508Y1415392D01*
X-195675Y1413933D01*
X-195467Y1411850D01*
X-195675Y1409767D01*
X-196508Y1408308D01*
X-197550Y1407058D01*
X-198800Y1406225D01*
X-200467Y1405600D01*
X-204633D01*
G01X-187675Y1411225D02*
X-181008D01*
X-181633Y1412683D01*
X-182675Y1413517D01*
X-184133Y1413933D01*
X-185592Y1413725D01*
X-186842Y1413100D01*
X-187675Y1411642D01*
X-188092Y1410391D01*
Y1409142D01*
X-187675Y1407892D01*
X-186633Y1406641D01*
X-185383Y1405808D01*
X-183925Y1405600D01*
X-182467Y1406017D01*
X-181008Y1407266D01*
G01X-170300Y1405600D02*
Y1416225D01*
X-169883Y1417266D01*
X-169050Y1417892D01*
X-167800Y1418100D01*
X-166550Y1417683D01*
X-165925Y1416642D01*
G01X-168425Y1413100D02*
X-172592D01*
G01X-153550Y1413933D02*
Y1405600D01*
G01Y1417266D02*
X-153967Y1417475D01*
Y1417892D01*
X-153550Y1418100D01*
X-153133Y1417892D01*
Y1417475D01*
X-153550Y1417266D01*
G01X-141592Y1405600D02*
Y1413933D01*
G01Y1411850D02*
X-140758Y1412892D01*
X-139508Y1413725D01*
X-137842Y1413933D01*
X-136383Y1413725D01*
X-135133Y1412892D01*
X-134508Y1411433D01*
Y1405600D01*
G01X-125675Y1411225D02*
X-119008D01*
X-119633Y1412683D01*
X-120675Y1413517D01*
X-122133Y1413933D01*
X-123592Y1413725D01*
X-124842Y1413100D01*
X-125675Y1411642D01*
X-126092Y1410391D01*
Y1409142D01*
X-125675Y1407892D01*
X-124633Y1406641D01*
X-123383Y1405808D01*
X-121925Y1405600D01*
X-120467Y1406017D01*
X-119008Y1407266D01*
G01X-91550Y1418100D02*
Y1405600D01*
G01X-94467Y1413933D02*
X-88633D01*
G01X-79592Y1405600D02*
Y1418100D01*
G01Y1412058D02*
X-78550Y1413100D01*
X-77508Y1413725D01*
X-75842Y1413933D01*
X-74592Y1413725D01*
X-73133Y1412892D01*
X-72508Y1411642D01*
Y1405600D01*
G01X-63675Y1411225D02*
X-57008D01*
X-57633Y1412683D01*
X-58675Y1413517D01*
X-60133Y1413933D01*
X-61592Y1413725D01*
X-62842Y1413100D01*
X-63675Y1411642D01*
X-64092Y1410391D01*
Y1409142D01*
X-63675Y1407892D01*
X-62633Y1406641D01*
X-61383Y1405808D01*
X-59925Y1405600D01*
X-58467Y1406017D01*
X-57008Y1407266D01*
G01X-47967Y1405600D02*
Y1413933D01*
G01Y1412267D02*
X-46925Y1413100D01*
X-45883Y1413725D01*
X-44425Y1413933D01*
X-43383Y1413725D01*
X-42133Y1413100D01*
G01X-35800Y1405600D02*
Y1413933D01*
G01Y1411642D02*
X-35175Y1412683D01*
X-34133Y1413517D01*
X-32675Y1413933D01*
X-31217Y1413517D01*
X-30175Y1412683D01*
X-29550Y1411642D01*
Y1405600D01*
G01Y1411642D02*
X-28925Y1412683D01*
X-27883Y1413517D01*
X-26425Y1413933D01*
X-24967Y1413517D01*
X-23925Y1412683D01*
X-23300Y1411433D01*
Y1405600D01*
G01X-10300D02*
Y1413933D01*
G01Y1412475D02*
X-11133Y1413308D01*
X-12383Y1413725D01*
X-13842Y1413933D01*
X-15300Y1413517D01*
X-16550Y1412683D01*
X-17384Y1411433D01*
X-17800Y1409767D01*
X-17384Y1408100D01*
X-16550Y1406850D01*
X-15300Y1406017D01*
X-13842Y1405600D01*
X-12383Y1405808D01*
X-11133Y1406433D01*
X-10300Y1407266D01*
G01X1450Y1405600D02*
Y1418100D01*
G01X29533Y1405600D02*
Y1413933D01*
G01Y1412267D02*
X30575Y1413100D01*
X31617Y1413725D01*
X33075Y1413933D01*
X34117Y1413725D01*
X35367Y1413100D01*
G01X44825Y1411225D02*
X51492D01*
X50867Y1412683D01*
X49825Y1413517D01*
X48367Y1413933D01*
X46908Y1413725D01*
X45658Y1413100D01*
X44825Y1411642D01*
X44408Y1410391D01*
Y1409142D01*
X44825Y1407892D01*
X45867Y1406641D01*
X47117Y1405808D01*
X48575Y1405600D01*
X50033Y1406017D01*
X51492Y1407266D01*
G01X63450Y1405600D02*
Y1418100D01*
G01X78950Y1413933D02*
Y1405600D01*
G01Y1417266D02*
X78533Y1417475D01*
Y1417892D01*
X78950Y1418100D01*
X79367Y1417892D01*
Y1417475D01*
X78950Y1417266D01*
G01X91325Y1411225D02*
X97992D01*
X97367Y1412683D01*
X96325Y1413517D01*
X94867Y1413933D01*
X93408Y1413725D01*
X92158Y1413100D01*
X91325Y1411642D01*
X90908Y1410391D01*
Y1409142D01*
X91325Y1407892D01*
X92367Y1406641D01*
X93617Y1405808D01*
X95075Y1405600D01*
X96533Y1406017D01*
X97992Y1407266D01*
G01X108700Y1405600D02*
Y1416225D01*
X109117Y1417266D01*
X109950Y1417892D01*
X111200Y1418100D01*
X112450Y1417683D01*
X113075Y1416642D01*
G01X110575Y1413100D02*
X106408D01*
G01X144283Y1412892D02*
X142825Y1413725D01*
X141575Y1413933D01*
X139908Y1413517D01*
X138658Y1412683D01*
X137825Y1411225D01*
X137616Y1409767D01*
X137825Y1408308D01*
X138658Y1407058D01*
X139908Y1406017D01*
X141575Y1405600D01*
X143033Y1406017D01*
X144283Y1406850D01*
G01X156450Y1405600D02*
X155200Y1405808D01*
X153950Y1406641D01*
X153116Y1408100D01*
X152700Y1409767D01*
X153116Y1411433D01*
X153950Y1412892D01*
X155200Y1413725D01*
X156450Y1413933D01*
X157700Y1413725D01*
X158950Y1412892D01*
X159783Y1411433D01*
X159992Y1409767D01*
X159783Y1408100D01*
X158950Y1406641D01*
X157700Y1405808D01*
X156450Y1405600D01*
G01X168408D02*
Y1413933D01*
G01Y1411850D02*
X169242Y1412892D01*
X170492Y1413725D01*
X172158Y1413933D01*
X173617Y1413725D01*
X174867Y1412892D01*
X175492Y1411433D01*
Y1405600D01*
G01X183908D02*
Y1413933D01*
G01Y1411850D02*
X184742Y1412892D01*
X185992Y1413725D01*
X187658Y1413933D01*
X189117Y1413725D01*
X190367Y1412892D01*
X190992Y1411433D01*
Y1405600D01*
G01X199825Y1411225D02*
X206492D01*
X205867Y1412683D01*
X204825Y1413517D01*
X203367Y1413933D01*
X201908Y1413725D01*
X200658Y1413100D01*
X199825Y1411642D01*
X199408Y1410391D01*
Y1409142D01*
X199825Y1407892D01*
X200867Y1406641D01*
X202117Y1405808D01*
X203575Y1405600D01*
X205033Y1406017D01*
X206492Y1407266D01*
G01X221783Y1412892D02*
X220325Y1413725D01*
X219075Y1413933D01*
X217408Y1413517D01*
X216158Y1412683D01*
X215325Y1411225D01*
X215116Y1409767D01*
X215325Y1408308D01*
X216158Y1407058D01*
X217408Y1406017D01*
X219075Y1405600D01*
X220533Y1406017D01*
X221783Y1406850D01*
G01X233950Y1418100D02*
Y1405600D01*
G01X231033Y1413933D02*
X236867D01*
G01X467467Y976983D02*
X476633Y986150D01*
G01X472050Y987817D02*
Y975317D01*
G01X476633Y976983D02*
X467467Y986150D01*
G01X465800Y981567D02*
X478300D01*
G01X482967Y976983D02*
X492133Y986150D01*
G01X487550Y987817D02*
Y975317D01*
G01X492133Y976983D02*
X482967Y986150D01*
G01X481300Y981567D02*
X493800D01*
G01X498467Y976983D02*
X507633Y986150D01*
G01X503050Y987817D02*
Y975317D01*
G01X507633Y976983D02*
X498467Y986150D01*
G01X496800Y981567D02*
X509300D01*
G01X513967Y976983D02*
X523133Y986150D01*
G01X518550Y987817D02*
Y975317D01*
G01X523133Y976983D02*
X513967Y986150D01*
G01X512300Y981567D02*
X524800D01*
G01X534050Y976983D02*
X533633Y977192D01*
Y977608D01*
X534050Y977817D01*
X534467Y977608D01*
Y977192D01*
X534050Y976983D01*
G01Y982608D02*
X533633Y982817D01*
Y983233D01*
X534050Y983442D01*
X534467Y983233D01*
Y982817D01*
X534050Y982608D01*
G01X562550Y989900D02*
X567550D01*
G01X565050D02*
Y977400D01*
G01X562550D02*
X567550D01*
G01X577633Y974275D02*
X579092Y973442D01*
X580758Y973233D01*
X582217Y973442D01*
X583467Y974483D01*
X584300Y975942D01*
Y985733D01*
G01Y984067D02*
X583467Y984900D01*
X582217Y985525D01*
X580758Y985733D01*
X579092Y985317D01*
X578050Y984483D01*
X577216Y983025D01*
X576800Y981567D01*
X577008Y980316D01*
X577842Y978858D01*
X579092Y977817D01*
X580758Y977400D01*
X582008Y977608D01*
X583467Y978441D01*
X584300Y979275D01*
G01X592508Y977400D02*
Y985733D01*
G01Y983650D02*
X593342Y984692D01*
X594592Y985525D01*
X596258Y985733D01*
X597717Y985525D01*
X598967Y984692D01*
X599592Y983233D01*
Y977400D01*
G01X611550D02*
X610300Y977608D01*
X609050Y978441D01*
X608216Y979900D01*
X607800Y981567D01*
X608216Y983233D01*
X609050Y984692D01*
X610300Y985525D01*
X611550Y985733D01*
X612800Y985525D01*
X614050Y984692D01*
X614883Y983233D01*
X615092Y981567D01*
X614883Y979900D01*
X614050Y978441D01*
X612800Y977608D01*
X611550Y977400D01*
G01X624133D02*
Y985733D01*
G01Y984067D02*
X625175Y984900D01*
X626217Y985525D01*
X627675Y985733D01*
X628717Y985525D01*
X629967Y984900D01*
G01X639425Y983025D02*
X646092D01*
X645467Y984483D01*
X644425Y985317D01*
X642967Y985733D01*
X641508Y985525D01*
X640258Y984900D01*
X639425Y983442D01*
X639008Y982191D01*
Y980942D01*
X639425Y979692D01*
X640467Y978441D01*
X641717Y977608D01*
X643175Y977400D01*
X644633Y977817D01*
X646092Y979066D01*
G01X673550Y977400D02*
Y989900D01*
X671050Y987400D01*
G01Y977400D02*
X676050D01*
G01X698300D02*
Y985733D01*
G01Y983442D02*
X698925Y984483D01*
X699967Y985317D01*
X701425Y985733D01*
X702883Y985317D01*
X703925Y984483D01*
X704550Y983442D01*
Y977400D01*
G01Y983442D02*
X705175Y984483D01*
X706217Y985317D01*
X707675Y985733D01*
X709133Y985317D01*
X710175Y984483D01*
X710800Y983233D01*
Y977400D01*
G01X720050Y985733D02*
Y977400D01*
G01Y989066D02*
X719633Y989275D01*
Y989692D01*
X720050Y989900D01*
X720467Y989692D01*
Y989275D01*
X720050Y989066D01*
G01X735550Y977400D02*
Y989900D01*
G01X761967Y977400D02*
Y989900D01*
X766133D01*
X767800Y989275D01*
X769050Y988442D01*
X770092Y987192D01*
X770925Y985733D01*
X771133Y983650D01*
X770925Y981567D01*
X770092Y980108D01*
X769050Y978858D01*
X767800Y978025D01*
X766133Y977400D01*
X761967D01*
G01X779342Y981567D02*
X784758D01*
G01X802133Y988858D02*
X800883Y989483D01*
X799425Y989900D01*
X797758D01*
X795883Y989275D01*
X794425Y988233D01*
X793383Y986983D01*
X792550Y984900D01*
X792341Y983025D01*
X792758Y981150D01*
X793383Y979900D01*
X794633Y978650D01*
X796092Y977817D01*
X797550Y977400D01*
X799008D01*
X800467Y977817D01*
X801717Y978441D01*
X802759Y979275D01*
G01X813050Y977400D02*
X811383Y977608D01*
X809925Y978441D01*
X808675Y979692D01*
X807841Y981150D01*
X807425Y982817D01*
Y984483D01*
X807841Y986150D01*
X808675Y987608D01*
X809925Y988858D01*
X811383Y989692D01*
X813050Y989900D01*
X814717Y989692D01*
X816175Y988858D01*
X817425Y987608D01*
X818259Y986150D01*
X818675Y984483D01*
Y982817D01*
X818259Y981150D01*
X817425Y979692D01*
X816175Y978441D01*
X814717Y977608D01*
X813050Y977400D01*
G01X823967D02*
Y989900D01*
X828133D01*
X829800Y989275D01*
X831050Y988442D01*
X832092Y987192D01*
X832925Y985733D01*
X833133Y983650D01*
X832925Y981567D01*
X832092Y980108D01*
X831050Y978858D01*
X829800Y978025D01*
X828133Y977400D01*
X823967D01*
G01X848217D02*
X839883D01*
Y989900D01*
X848217D01*
G01X844883Y983858D02*
X839883D01*
G01X471658Y1022300D02*
Y1034800D01*
X481242Y1022300D01*
Y1034800D01*
G01X491950Y1022300D02*
X490700Y1022508D01*
X489450Y1023341D01*
X488616Y1024800D01*
X488200Y1026467D01*
X488616Y1028133D01*
X489450Y1029592D01*
X490700Y1030425D01*
X491950Y1030633D01*
X493200Y1030425D01*
X494450Y1029592D01*
X495283Y1028133D01*
X495492Y1026467D01*
X495283Y1024800D01*
X494450Y1023341D01*
X493200Y1022508D01*
X491950Y1022300D01*
G01X507450Y1034800D02*
Y1022300D01*
G01X504533Y1030633D02*
X510367D01*
G01X519825Y1027925D02*
X526492D01*
X525867Y1029383D01*
X524825Y1030217D01*
X523367Y1030633D01*
X521908Y1030425D01*
X520658Y1029800D01*
X519825Y1028342D01*
X519408Y1027091D01*
Y1025842D01*
X519825Y1024592D01*
X520867Y1023341D01*
X522117Y1022508D01*
X523575Y1022300D01*
X525033Y1022717D01*
X526492Y1023966D01*
G01X535325Y1023758D02*
X536367Y1022925D01*
X537825Y1022300D01*
X539075D01*
X540325Y1022717D01*
X541158Y1023341D01*
X541575Y1024175D01*
X541367Y1025425D01*
X540533Y1026050D01*
X536783Y1027300D01*
X535950Y1028758D01*
X536367Y1029800D01*
X537200Y1030425D01*
X538450Y1030633D01*
X539700Y1030425D01*
X540950Y1029800D01*
G01X553950Y1021883D02*
X553533Y1022092D01*
Y1022508D01*
X553950Y1022717D01*
X554367Y1022508D01*
Y1022092D01*
X553950Y1021883D01*
G01Y1027508D02*
X553533Y1027717D01*
Y1028133D01*
X553950Y1028342D01*
X554367Y1028133D01*
Y1027717D01*
X553950Y1027508D01*
G54D11*
G01X-199967Y1205600D02*
X-206633D01*
Y1215600D01*
X-199967D01*
G01X-202633Y1210767D02*
X-206633D01*
G01X-195500Y1205600D02*
X-188500Y1215600D01*
G01X-195500D02*
X-188500Y1205600D01*
G01X-180700Y1205267D02*
X-181033Y1205433D01*
Y1205767D01*
X-180700Y1205933D01*
X-180367Y1205767D01*
Y1205433D01*
X-180700Y1205267D01*
G01Y1209766D02*
X-181033Y1209933D01*
Y1210267D01*
X-180700Y1210433D01*
X-180367Y1210267D01*
Y1209933D01*
X-180700Y1209766D01*
G01X-161267Y1205600D02*
Y1215600D01*
X-154933D01*
G01X-157267Y1210767D02*
X-161267D01*
G01X-150133Y1215600D02*
Y1205600D01*
X-143467D01*
G01X-139667D02*
X-135500Y1215600D01*
X-131333Y1205600D01*
G01X-132833Y1209100D02*
X-138167D01*
G01X-127700Y1206933D02*
X-126367Y1206100D01*
X-124867Y1205600D01*
X-123533D01*
X-122200Y1206100D01*
X-121200Y1206933D01*
X-120700Y1208100D01*
X-121033Y1209266D01*
X-121867Y1210267D01*
X-123367Y1210933D01*
X-125367Y1211267D01*
X-126533Y1211933D01*
X-127033Y1213100D01*
X-126700Y1214267D01*
X-125867Y1215100D01*
X-124700Y1215600D01*
X-123533D01*
X-122367Y1215267D01*
X-121367Y1214433D01*
G01X-116400Y1205600D02*
Y1215600D01*
G01X-109400D02*
Y1205600D01*
G01Y1210600D02*
X-116400D01*
G01X-90300Y1215600D02*
Y1205600D01*
G01X-94133Y1215600D02*
X-86467D01*
G01X-82333Y1205600D02*
Y1215600D01*
X-78167D01*
X-76833Y1215100D01*
X-76000Y1214433D01*
X-75667Y1213100D01*
X-76000Y1211767D01*
X-77000Y1210933D01*
X-78167Y1210433D01*
X-82333D01*
G01X-78167D02*
X-75667Y1205600D01*
G01X-67700D02*
Y1215600D01*
X-69700Y1213600D01*
G01Y1205600D02*
X-65700D01*
G01X-56400Y1215600D02*
X-57734Y1215267D01*
X-58733Y1214433D01*
X-59400Y1213433D01*
X-59900Y1212100D01*
X-60067Y1210600D01*
X-59900Y1209100D01*
X-59400Y1207767D01*
X-58733Y1206766D01*
X-57734Y1205933D01*
X-56400Y1205600D01*
X-55067Y1205933D01*
X-54067Y1206766D01*
X-53400Y1207767D01*
X-52900Y1209100D01*
X-52733Y1210600D01*
X-52900Y1212100D01*
X-53400Y1213433D01*
X-54067Y1214433D01*
X-55067Y1215267D01*
X-56400Y1215600D01*
G01X-48767Y1207600D02*
X-47767Y1206433D01*
X-46434Y1205767D01*
X-44933Y1205600D01*
X-43600Y1205767D01*
X-42267Y1206600D01*
X-41433Y1207600D01*
X-41267Y1208600D01*
X-41600Y1209766D01*
X-42767Y1210600D01*
X-43933Y1210933D01*
X-45433D01*
G01X-43933D02*
X-42933Y1211433D01*
X-42100Y1212266D01*
X-41767Y1213267D01*
X-42100Y1214267D01*
X-42933Y1215100D01*
X-44433Y1215600D01*
X-45933Y1215433D01*
X-47433Y1214767D01*
G01X-38800Y1202267D02*
X-28800D01*
G01X-25333Y1206766D02*
X-24167Y1205933D01*
X-22833Y1205600D01*
X-21500Y1205933D01*
X-20333Y1206933D01*
X-19500Y1208433D01*
X-19167Y1209933D01*
Y1211767D01*
X-19500Y1213267D01*
X-20333Y1214600D01*
X-21333Y1215267D01*
X-22500Y1215600D01*
X-23834Y1215267D01*
X-24833Y1214600D01*
X-25500Y1213600D01*
X-25833Y1212266D01*
X-25500Y1211100D01*
X-24667Y1209933D01*
X-23667Y1209266D01*
X-22500Y1209100D01*
X-21167Y1209433D01*
X-20167Y1210267D01*
X-19167Y1211767D01*
G01X-14867Y1207600D02*
X-13867Y1206433D01*
X-12534Y1205767D01*
X-11033Y1205600D01*
X-9700Y1205767D01*
X-8367Y1206600D01*
X-7533Y1207600D01*
X-7367Y1208600D01*
X-7700Y1209766D01*
X-8867Y1210600D01*
X-10033Y1210933D01*
X-11533D01*
G01X-10033D02*
X-9033Y1211433D01*
X-8200Y1212266D01*
X-7867Y1213267D01*
X-8200Y1214267D01*
X-9033Y1215100D01*
X-10533Y1215600D01*
X-12033Y1215433D01*
X-13533Y1214767D01*
G01X-4900Y1202267D02*
X5100D01*
G01X7733Y1207600D02*
X8733Y1206433D01*
X10066Y1205767D01*
X11567Y1205600D01*
X12900Y1205767D01*
X14233Y1206600D01*
X15067Y1207600D01*
X15233Y1208600D01*
X14900Y1209766D01*
X13733Y1210600D01*
X12567Y1210933D01*
X11067D01*
G01X12567D02*
X13567Y1211433D01*
X14400Y1212266D01*
X14733Y1213267D01*
X14400Y1214267D01*
X13567Y1215100D01*
X12067Y1215600D01*
X10567Y1215433D01*
X9067Y1214767D01*
G01X22700Y1215600D02*
X21366Y1215267D01*
X20367Y1214433D01*
X19700Y1213433D01*
X19200Y1212100D01*
X19033Y1210600D01*
X19200Y1209100D01*
X19700Y1207767D01*
X20367Y1206766D01*
X21366Y1205933D01*
X22700Y1205600D01*
X24033Y1205933D01*
X25033Y1206766D01*
X25700Y1207767D01*
X26200Y1209100D01*
X26367Y1210600D01*
X26200Y1212100D01*
X25700Y1213433D01*
X25033Y1214433D01*
X24033Y1215267D01*
X22700Y1215600D01*
G01X34000Y1205267D02*
X33667Y1205433D01*
Y1205767D01*
X34000Y1205933D01*
X34333Y1205767D01*
Y1205433D01*
X34000Y1205267D01*
G01Y1209766D02*
X33667Y1209933D01*
Y1210267D01*
X34000Y1210433D01*
X34333Y1210267D01*
Y1209933D01*
X34000Y1209766D01*
G01X-192967Y1347600D02*
X-191967Y1346433D01*
X-190634Y1345767D01*
X-189133Y1345600D01*
X-187800Y1345767D01*
X-186467Y1346600D01*
X-185633Y1347600D01*
X-185467Y1348600D01*
X-185800Y1349766D01*
X-186967Y1350600D01*
X-188133Y1350933D01*
X-189633D01*
G01X-188133D02*
X-187133Y1351433D01*
X-186300Y1352266D01*
X-185967Y1353267D01*
X-186300Y1354267D01*
X-187133Y1355100D01*
X-188633Y1355600D01*
X-190133Y1355433D01*
X-191633Y1354767D01*
G01X-178000Y1345267D02*
X-178333Y1345433D01*
Y1345767D01*
X-178000Y1345933D01*
X-177667Y1345767D01*
Y1345433D01*
X-178000Y1345267D01*
G01X-192467Y1369933D02*
X-191467Y1370933D01*
X-190300Y1371433D01*
X-188967Y1371600D01*
X-187300Y1371267D01*
X-186133Y1370433D01*
X-185800Y1369433D01*
X-185967Y1368433D01*
X-186633Y1367600D01*
X-189967Y1365933D01*
X-191467Y1364767D01*
X-192467Y1363100D01*
X-192800Y1361600D01*
X-185800D01*
G01X-178000Y1361267D02*
X-178333Y1361433D01*
Y1361767D01*
X-178000Y1361933D01*
X-177667Y1361767D01*
Y1361433D01*
X-178000Y1361267D01*
G01X-189300Y1377600D02*
Y1387600D01*
X-191300Y1385600D01*
G01Y1377600D02*
X-187300D01*
G01X-178000Y1377267D02*
X-178333Y1377433D01*
Y1377767D01*
X-178000Y1377933D01*
X-177667Y1377767D01*
Y1377433D01*
X-178000Y1377267D01*
G01X-158567Y1377600D02*
Y1387600D01*
X-152233D01*
G01X-154567Y1382767D02*
X-158567D01*
G01X-147433Y1387600D02*
Y1377600D01*
X-140767D01*
G01X-136967D02*
X-132800Y1387600D01*
X-128633Y1377600D01*
G01X-130133Y1381100D02*
X-135467D01*
G01X-125000Y1378933D02*
X-123667Y1378100D01*
X-122167Y1377600D01*
X-120833D01*
X-119500Y1378100D01*
X-118500Y1378933D01*
X-118000Y1380100D01*
X-118333Y1381266D01*
X-119167Y1382267D01*
X-120667Y1382933D01*
X-122667Y1383267D01*
X-123833Y1383933D01*
X-124333Y1385100D01*
X-124000Y1386267D01*
X-123167Y1387100D01*
X-122000Y1387600D01*
X-120833D01*
X-119667Y1387267D01*
X-118667Y1386433D01*
G01X-113700Y1377600D02*
Y1387600D01*
G01X-106700D02*
Y1377600D01*
G01Y1382600D02*
X-113700D01*
G01X-87600Y1387600D02*
Y1377600D01*
G01X-91433Y1387600D02*
X-83767D01*
G01X-79800Y1377600D02*
Y1387600D01*
G01X-72800D02*
Y1377600D01*
G01Y1382600D02*
X-79800D01*
G01X-69333Y1377600D02*
Y1387600D01*
X-65000Y1379267D01*
X-60667Y1387600D01*
Y1377600D01*
G01X-57033Y1387600D02*
Y1377600D01*
X-50367D01*
G01X-42400D02*
Y1387600D01*
X-44400Y1385600D01*
G01Y1377600D02*
X-40400D01*
G01X-31100Y1387600D02*
X-32434Y1387267D01*
X-33433Y1386433D01*
X-34100Y1385433D01*
X-34600Y1384100D01*
X-34767Y1382600D01*
X-34600Y1381100D01*
X-34100Y1379767D01*
X-33433Y1378766D01*
X-32434Y1377933D01*
X-31100Y1377600D01*
X-29767Y1377933D01*
X-28767Y1378766D01*
X-28100Y1379767D01*
X-27600Y1381100D01*
X-27433Y1382600D01*
X-27600Y1384100D01*
X-28100Y1385433D01*
X-28767Y1386433D01*
X-29767Y1387267D01*
X-31100Y1387600D01*
G01X-8500Y1377267D02*
X-8833Y1377433D01*
Y1377767D01*
X-8500Y1377933D01*
X-8167Y1377767D01*
Y1377433D01*
X-8500Y1377267D01*
G01Y1381766D02*
X-8833Y1381933D01*
Y1382267D01*
X-8500Y1382433D01*
X-8167Y1382267D01*
Y1381933D01*
X-8500Y1381766D01*
G01X10933Y1377600D02*
Y1387600D01*
X17267D01*
G01X14933Y1382767D02*
X10933D01*
G01X22567Y1384266D02*
Y1379600D01*
X23233Y1378433D01*
X24233Y1377767D01*
X25400Y1377600D01*
X26567Y1377767D01*
X27567Y1378433D01*
X28233Y1379600D01*
G01Y1377600D02*
Y1384266D01*
G01X36700Y1377600D02*
Y1387600D01*
G01X48000Y1377600D02*
Y1387600D01*
G01X73267Y1383433D02*
X72100Y1384100D01*
X71100Y1384266D01*
X69767Y1383933D01*
X68767Y1383267D01*
X68100Y1382100D01*
X67933Y1380933D01*
X68100Y1379767D01*
X68767Y1378766D01*
X69767Y1377933D01*
X71100Y1377600D01*
X72267Y1377933D01*
X73267Y1378600D01*
G01X81900Y1377600D02*
X80900Y1377767D01*
X79900Y1378433D01*
X79233Y1379600D01*
X78900Y1380933D01*
X79233Y1382267D01*
X79900Y1383433D01*
X80900Y1384100D01*
X81900Y1384266D01*
X82900Y1384100D01*
X83900Y1383433D01*
X84567Y1382267D01*
X84733Y1380933D01*
X84567Y1379600D01*
X83900Y1378433D01*
X82900Y1377767D01*
X81900Y1377600D01*
G01X90367D02*
Y1384266D01*
G01Y1382600D02*
X91033Y1383433D01*
X92033Y1384100D01*
X93367Y1384266D01*
X94533Y1384100D01*
X95533Y1383433D01*
X96033Y1382267D01*
Y1377600D01*
G01X104500Y1387600D02*
Y1377600D01*
G01X102167Y1384266D02*
X106833D01*
G01X118800Y1377600D02*
Y1384266D01*
G01Y1383100D02*
X118133Y1383767D01*
X117133Y1384100D01*
X115967Y1384266D01*
X114800Y1383933D01*
X113800Y1383267D01*
X113133Y1382267D01*
X112800Y1380933D01*
X113133Y1379600D01*
X113800Y1378600D01*
X114800Y1377933D01*
X115967Y1377600D01*
X117133Y1377767D01*
X118133Y1378267D01*
X118800Y1378933D01*
G01X129767Y1383433D02*
X128600Y1384100D01*
X127600Y1384266D01*
X126267Y1383933D01*
X125267Y1383267D01*
X124600Y1382100D01*
X124433Y1380933D01*
X124600Y1379767D01*
X125267Y1378766D01*
X126267Y1377933D01*
X127600Y1377600D01*
X128767Y1377933D01*
X129767Y1378600D01*
G01X138400Y1387600D02*
Y1377600D01*
G01X136067Y1384266D02*
X140733D01*
G01X-143667Y684900D02*
X-150333D01*
Y694900D01*
X-143667D01*
G01X-146333Y690067D02*
X-150333D01*
G01X-139200Y684900D02*
X-132200Y694900D01*
G01X-139200D02*
X-132200Y684900D01*
G01X-124400Y684567D02*
X-124733Y684733D01*
Y685067D01*
X-124400Y685233D01*
X-124067Y685067D01*
Y684733D01*
X-124400Y684567D01*
G01Y689066D02*
X-124733Y689233D01*
Y689567D01*
X-124400Y689733D01*
X-124067Y689567D01*
Y689233D01*
X-124400Y689066D01*
G01X-104967Y684900D02*
Y694900D01*
X-98633D01*
G01X-100967Y690067D02*
X-104967D01*
G01X-93833Y694900D02*
Y684900D01*
X-87167D01*
G01X-83367D02*
X-79200Y694900D01*
X-75033Y684900D01*
G01X-76533Y688400D02*
X-81867D01*
G01X-71400Y686233D02*
X-70067Y685400D01*
X-68567Y684900D01*
X-67233D01*
X-65900Y685400D01*
X-64900Y686233D01*
X-64400Y687400D01*
X-64733Y688566D01*
X-65567Y689567D01*
X-67067Y690233D01*
X-69067Y690567D01*
X-70233Y691233D01*
X-70733Y692400D01*
X-70400Y693567D01*
X-69567Y694400D01*
X-68400Y694900D01*
X-67233D01*
X-66067Y694567D01*
X-65067Y693733D01*
G01X-60100Y684900D02*
Y694900D01*
G01X-53100D02*
Y684900D01*
G01Y689900D02*
X-60100D01*
G01X-34000Y694900D02*
Y684900D01*
G01X-37833Y694900D02*
X-30167D01*
G01X-26033Y684900D02*
Y694900D01*
X-21867D01*
X-20533Y694400D01*
X-19700Y693733D01*
X-19367Y692400D01*
X-19700Y691067D01*
X-20700Y690233D01*
X-21867Y689733D01*
X-26033D01*
G01X-21867D02*
X-19367Y684900D01*
G01X-14567Y689066D02*
X-13400Y690233D01*
X-12400Y690900D01*
X-11067Y691233D01*
X-9900Y690900D01*
X-9067Y690233D01*
X-8400Y689233D01*
X-8233Y688067D01*
X-8400Y687067D01*
X-9067Y686066D01*
X-10067Y685233D01*
X-11233Y684900D01*
X-12567Y685233D01*
X-13733Y686233D01*
X-14400Y687733D01*
X-14567Y689400D01*
X-14233Y691566D01*
X-13733Y692733D01*
X-12900Y693900D01*
X-11733Y694733D01*
X-10567Y694900D01*
X-9400Y694567D01*
X-8567Y693733D01*
G01X-100Y694900D02*
X-1434Y694567D01*
X-2433Y693733D01*
X-3100Y692733D01*
X-3600Y691400D01*
X-3767Y689900D01*
X-3600Y688400D01*
X-3100Y687067D01*
X-2433Y686066D01*
X-1434Y685233D01*
X-100Y684900D01*
X1233Y685233D01*
X2233Y686066D01*
X2900Y687067D01*
X3400Y688400D01*
X3567Y689900D01*
X3400Y691400D01*
X2900Y692733D01*
X2233Y693733D01*
X1233Y694567D01*
X-100Y694900D01*
G01X7700Y684900D02*
X14700Y694900D01*
G01X7700D02*
X14700Y684900D01*
G01X22500D02*
Y694900D01*
X20500Y692900D01*
G01Y684900D02*
X24500D01*
G01X33800D02*
Y694900D01*
X31800Y692900D01*
G01Y684900D02*
X35800D01*
G01X42267Y686066D02*
X43433Y685233D01*
X44767Y684900D01*
X46100Y685233D01*
X47267Y686233D01*
X48100Y687733D01*
X48433Y689233D01*
Y691067D01*
X48100Y692567D01*
X47267Y693900D01*
X46267Y694567D01*
X45100Y694900D01*
X43766Y694567D01*
X42767Y693900D01*
X42100Y692900D01*
X41767Y691566D01*
X42100Y690400D01*
X42933Y689233D01*
X43933Y688566D01*
X45100Y688400D01*
X46433Y688733D01*
X47433Y689567D01*
X48433Y691067D01*
G01X51400Y681567D02*
X61400D01*
G01X64533Y693233D02*
X65533Y694233D01*
X66700Y694733D01*
X68033Y694900D01*
X69700Y694567D01*
X70867Y693733D01*
X71200Y692733D01*
X71033Y691733D01*
X70367Y690900D01*
X67033Y689233D01*
X65533Y688067D01*
X64533Y686400D01*
X64200Y684900D01*
X71200D01*
G01X79000Y694900D02*
X77666Y694567D01*
X76667Y693733D01*
X76000Y692733D01*
X75500Y691400D01*
X75333Y689900D01*
X75500Y688400D01*
X76000Y687067D01*
X76667Y686066D01*
X77666Y685233D01*
X79000Y684900D01*
X80333Y685233D01*
X81333Y686066D01*
X82000Y687067D01*
X82500Y688400D01*
X82667Y689900D01*
X82500Y691400D01*
X82000Y692733D01*
X81333Y693733D01*
X80333Y694567D01*
X79000Y694900D01*
G01X86800Y684900D02*
X93800Y694900D01*
G01X86800D02*
X93800Y684900D01*
G01X97933Y686900D02*
X98933Y685733D01*
X100266Y685067D01*
X101767Y684900D01*
X103100Y685067D01*
X104433Y685900D01*
X105267Y686900D01*
X105433Y687900D01*
X105100Y689066D01*
X103933Y689900D01*
X102767Y690233D01*
X101267D01*
G01X102767D02*
X103767Y690733D01*
X104600Y691566D01*
X104933Y692567D01*
X104600Y693567D01*
X103767Y694400D01*
X102267Y694900D01*
X100767Y694733D01*
X99267Y694067D01*
G01X112900Y694900D02*
X111566Y694567D01*
X110567Y693733D01*
X109900Y692733D01*
X109400Y691400D01*
X109233Y689900D01*
X109400Y688400D01*
X109900Y687067D01*
X110567Y686066D01*
X111566Y685233D01*
X112900Y684900D01*
X114233Y685233D01*
X115233Y686066D01*
X115900Y687067D01*
X116400Y688400D01*
X116567Y689900D01*
X116400Y691400D01*
X115900Y692733D01*
X115233Y693733D01*
X114233Y694567D01*
X112900Y694900D01*
G01X-126967Y710900D02*
X-133633D01*
Y720900D01*
X-126967D01*
G01X-129633Y716067D02*
X-133633D01*
G01X-119000Y710567D02*
X-119333Y710733D01*
Y711067D01*
X-119000Y711233D01*
X-118667Y711067D01*
Y710733D01*
X-119000Y710567D01*
G01Y715066D02*
X-119333Y715233D01*
Y715567D01*
X-119000Y715733D01*
X-118667Y715567D01*
Y715233D01*
X-119000Y715066D01*
G01X-154033Y734700D02*
Y744700D01*
X-146367Y734700D01*
Y744700D01*
G01X-143067Y734700D02*
X-138900Y744700D01*
X-134733Y734700D01*
G01X-136233Y738200D02*
X-141567D01*
G01X-131933Y734700D02*
Y744700D01*
X-127600Y736367D01*
X-123267Y744700D01*
Y734700D01*
G01X-112967D02*
X-119633D01*
Y744700D01*
X-112967D01*
G01X-115633Y739867D02*
X-119633D01*
G01X-105000Y734367D02*
X-105333Y734533D01*
Y734867D01*
X-105000Y735033D01*
X-104667Y734867D01*
Y734533D01*
X-105000Y734367D01*
G01Y738866D02*
X-105333Y739033D01*
Y739367D01*
X-105000Y739533D01*
X-104667Y739367D01*
Y739033D01*
X-105000Y738866D01*
G01X-82400Y744700D02*
Y734700D01*
G01X-86233Y744700D02*
X-78567D01*
G01X-74433Y734700D02*
Y744700D01*
X-70267D01*
X-68933Y744200D01*
X-68100Y743533D01*
X-67767Y742200D01*
X-68100Y740867D01*
X-69100Y740033D01*
X-70267Y739533D01*
X-74433D01*
G01X-70267D02*
X-67767Y734700D01*
G01X-63967D02*
X-59800Y744700D01*
X-55633Y734700D01*
G01X-57133Y738200D02*
X-62467D01*
G01X-52000Y734700D02*
X-45000Y744700D01*
G01X-52000D02*
X-45000Y734700D01*
G01X-35867Y740033D02*
X-35200Y740533D01*
X-34700Y741366D01*
X-34367Y742533D01*
X-34700Y743533D01*
X-35367Y744200D01*
X-36533Y744700D01*
X-41033D01*
Y734700D01*
X-35533D01*
X-34367Y735367D01*
X-33700Y736367D01*
X-33367Y737533D01*
X-33700Y738700D01*
X-34700Y739700D01*
X-35867Y740033D01*
X-41033D01*
G01X-30900Y731367D02*
X-20900D01*
G01X-10933Y743867D02*
X-11933Y744367D01*
X-13100Y744700D01*
X-14433D01*
X-15934Y744200D01*
X-17100Y743367D01*
X-17933Y742367D01*
X-18600Y740700D01*
X-18767Y739200D01*
X-18433Y737700D01*
X-17933Y736700D01*
X-16933Y735700D01*
X-15767Y735033D01*
X-14600Y734700D01*
X-13433D01*
X-12267Y735033D01*
X-11267Y735533D01*
X-10433Y736200D01*
G01X-6800Y734700D02*
X200Y744700D01*
G01X-6800D02*
X200Y734700D01*
G01X4333D02*
Y744700D01*
X7667D01*
X9000Y744200D01*
X10000Y743533D01*
X10833Y742533D01*
X11500Y741366D01*
X11667Y739700D01*
X11500Y738033D01*
X10833Y736867D01*
X10000Y735866D01*
X9000Y735200D01*
X7667Y734700D01*
X4333D01*
G01X-114467Y800300D02*
X-121133D01*
Y810300D01*
X-114467D01*
G01X-117133Y805467D02*
X-121133D01*
G01X-127767Y879300D02*
Y889300D01*
X-124433D01*
X-123100Y888800D01*
X-122100Y888133D01*
X-121267Y887133D01*
X-120600Y885966D01*
X-120433Y884300D01*
X-120600Y882633D01*
X-121267Y881467D01*
X-122100Y880466D01*
X-123100Y879800D01*
X-124433Y879300D01*
X-127767D01*
G01X-116067Y1000900D02*
X-122733D01*
Y1010900D01*
X-116067D01*
G01X-118733Y1006067D02*
X-122733D01*
G01X-111433Y1010900D02*
Y1000900D01*
X-104767D01*
G01X-100133Y1010900D02*
Y1000900D01*
X-93467D01*
G01X-87500Y1010900D02*
X-83500D01*
G01X-85500D02*
Y1000900D01*
G01X-87500D02*
X-83500D01*
G01X-77533D02*
Y1010900D01*
X-73533D01*
X-72200Y1010400D01*
X-71200Y1009233D01*
X-70867Y1007900D01*
X-71200Y1006567D01*
X-72033Y1005567D01*
X-73533Y1005066D01*
X-77533D01*
G01X-66400Y1002233D02*
X-65067Y1001400D01*
X-63567Y1000900D01*
X-62233D01*
X-60900Y1001400D01*
X-59900Y1002233D01*
X-59400Y1003400D01*
X-59733Y1004566D01*
X-60567Y1005567D01*
X-62067Y1006233D01*
X-64067Y1006567D01*
X-65233Y1007233D01*
X-65733Y1008400D01*
X-65400Y1009567D01*
X-64567Y1010400D01*
X-63400Y1010900D01*
X-62233D01*
X-61067Y1010567D01*
X-60067Y1009733D01*
G01X-48267Y1000900D02*
X-54933D01*
Y1010900D01*
X-48267D01*
G01X-50933Y1006067D02*
X-54933D01*
G01X-29000Y1010900D02*
Y1000900D01*
G01X-32833Y1010900D02*
X-25167D01*
G01X-20533Y1000900D02*
Y1010900D01*
G01Y1006067D02*
X-19700Y1006900D01*
X-18867Y1007400D01*
X-17533Y1007566D01*
X-16533Y1007400D01*
X-15367Y1006733D01*
X-14867Y1005733D01*
Y1000900D01*
G01X-8900Y1005400D02*
X-3567D01*
X-4067Y1006567D01*
X-4900Y1007233D01*
X-6067Y1007566D01*
X-7233Y1007400D01*
X-8233Y1006900D01*
X-8900Y1005733D01*
X-9233Y1004733D01*
Y1003733D01*
X-8900Y1002733D01*
X-8067Y1001733D01*
X-7067Y1001067D01*
X-5900Y1000900D01*
X-4733Y1001233D01*
X-3567Y1002233D01*
G01X2567Y1000900D02*
Y1007566D01*
G01Y1006233D02*
X3400Y1006900D01*
X4233Y1007400D01*
X5400Y1007566D01*
X6233Y1007400D01*
X7233Y1006900D01*
G01X11200Y1000900D02*
Y1007566D01*
G01Y1005733D02*
X11700Y1006567D01*
X12533Y1007233D01*
X13700Y1007566D01*
X14866Y1007233D01*
X15700Y1006567D01*
X16200Y1005733D01*
Y1000900D01*
G01Y1005733D02*
X16700Y1006567D01*
X17533Y1007233D01*
X18700Y1007566D01*
X19867Y1007233D01*
X20700Y1006567D01*
X21200Y1005567D01*
Y1000900D01*
G01X30500D02*
Y1007566D01*
G01Y1006400D02*
X29833Y1007067D01*
X28833Y1007400D01*
X27667Y1007566D01*
X26500Y1007233D01*
X25500Y1006567D01*
X24833Y1005567D01*
X24500Y1004233D01*
X24833Y1002900D01*
X25500Y1001900D01*
X26500Y1001233D01*
X27667Y1000900D01*
X28833Y1001067D01*
X29833Y1001567D01*
X30500Y1002233D01*
G01X38800Y1000900D02*
Y1010900D01*
G01X-117600Y1242800D02*
X-113600D01*
G01X-115600D02*
Y1232800D01*
G01X-117600D02*
X-113600D01*
G01X-107133D02*
Y1239466D01*
G01Y1237800D02*
X-106467Y1238633D01*
X-105467Y1239300D01*
X-104133Y1239466D01*
X-102967Y1239300D01*
X-101967Y1238633D01*
X-101467Y1237467D01*
Y1232800D01*
G01X-95833D02*
Y1239466D01*
G01Y1237800D02*
X-95167Y1238633D01*
X-94167Y1239300D01*
X-92833Y1239466D01*
X-91667Y1239300D01*
X-90667Y1238633D01*
X-90167Y1237467D01*
Y1232800D01*
G01X-84200Y1237300D02*
X-78867D01*
X-79367Y1238467D01*
X-80200Y1239133D01*
X-81367Y1239466D01*
X-82533Y1239300D01*
X-83533Y1238800D01*
X-84200Y1237633D01*
X-84533Y1236633D01*
Y1235633D01*
X-84200Y1234633D01*
X-83367Y1233633D01*
X-82367Y1232967D01*
X-81200Y1232800D01*
X-80033Y1233133D01*
X-78867Y1234133D01*
G01X-72733Y1232800D02*
Y1239466D01*
G01Y1238133D02*
X-71900Y1238800D01*
X-71067Y1239300D01*
X-69900Y1239466D01*
X-69067Y1239300D01*
X-68067Y1238800D01*
G01X-51467Y1232800D02*
Y1242800D01*
X-48133D01*
X-46800Y1242300D01*
X-45800Y1241633D01*
X-44967Y1240633D01*
X-44300Y1239466D01*
X-44133Y1237800D01*
X-44300Y1236133D01*
X-44967Y1234967D01*
X-45800Y1233966D01*
X-46800Y1233300D01*
X-48133Y1232800D01*
X-51467D01*
G01X-36500Y1239466D02*
Y1232800D01*
G01Y1242133D02*
X-36833Y1242300D01*
Y1242633D01*
X-36500Y1242800D01*
X-36167Y1242633D01*
Y1242300D01*
X-36500Y1242133D01*
G01X-22200Y1232800D02*
Y1239466D01*
G01Y1238300D02*
X-22867Y1238967D01*
X-23867Y1239300D01*
X-25033Y1239466D01*
X-26200Y1239133D01*
X-27200Y1238467D01*
X-27867Y1237467D01*
X-28200Y1236133D01*
X-27867Y1234800D01*
X-27200Y1233800D01*
X-26200Y1233133D01*
X-25033Y1232800D01*
X-23867Y1232967D01*
X-22867Y1233467D01*
X-22200Y1234133D01*
G01X-18900Y1232800D02*
Y1239466D01*
G01Y1237633D02*
X-18400Y1238467D01*
X-17567Y1239133D01*
X-16400Y1239466D01*
X-15234Y1239133D01*
X-14400Y1238467D01*
X-13900Y1237633D01*
Y1232800D01*
G01Y1237633D02*
X-13400Y1238467D01*
X-12567Y1239133D01*
X-11400Y1239466D01*
X-10233Y1239133D01*
X-9400Y1238467D01*
X-8900Y1237467D01*
Y1232800D01*
G01X-5100Y1237300D02*
X233D01*
X-267Y1238467D01*
X-1100Y1239133D01*
X-2267Y1239466D01*
X-3433Y1239300D01*
X-4433Y1238800D01*
X-5100Y1237633D01*
X-5433Y1236633D01*
Y1235633D01*
X-5100Y1234633D01*
X-4267Y1233633D01*
X-3267Y1232967D01*
X-2100Y1232800D01*
X-933Y1233133D01*
X233Y1234133D01*
G01X8700Y1242800D02*
Y1232800D01*
G01X6367Y1239466D02*
X11033D01*
G01X17500Y1237300D02*
X22833D01*
X22333Y1238467D01*
X21500Y1239133D01*
X20333Y1239466D01*
X19167Y1239300D01*
X18167Y1238800D01*
X17500Y1237633D01*
X17167Y1236633D01*
Y1235633D01*
X17500Y1234633D01*
X18333Y1233633D01*
X19333Y1232967D01*
X20500Y1232800D01*
X21667Y1233133D01*
X22833Y1234133D01*
G01X28967Y1232800D02*
Y1239466D01*
G01Y1238133D02*
X29800Y1238800D01*
X30633Y1239300D01*
X31800Y1239466D01*
X32633Y1239300D01*
X33633Y1238800D01*
G01X-160300Y1369600D02*
X-157967Y1359600D01*
X-155300Y1369600D01*
X-152633Y1359600D01*
X-150300Y1369600D01*
G01X-144000Y1366266D02*
Y1359600D01*
G01Y1368933D02*
X-144333Y1369100D01*
Y1369433D01*
X-144000Y1369600D01*
X-143667Y1369433D01*
Y1369100D01*
X-144000Y1368933D01*
G01X-135200Y1360766D02*
X-134367Y1360100D01*
X-133200Y1359600D01*
X-132200D01*
X-131200Y1359933D01*
X-130533Y1360433D01*
X-130200Y1361100D01*
X-130367Y1362100D01*
X-131033Y1362600D01*
X-134034Y1363600D01*
X-134700Y1364767D01*
X-134367Y1365600D01*
X-133700Y1366100D01*
X-132700Y1366266D01*
X-131700Y1366100D01*
X-130700Y1365600D01*
G01X-121400Y1369600D02*
Y1359600D01*
G01X-123733Y1366266D02*
X-119067D01*
G01X-112433Y1359600D02*
Y1366266D01*
G01Y1364933D02*
X-111600Y1365600D01*
X-110767Y1366100D01*
X-109600Y1366266D01*
X-108767Y1366100D01*
X-107767Y1365600D01*
G01X-98800Y1359600D02*
X-99800Y1359767D01*
X-100800Y1360433D01*
X-101467Y1361600D01*
X-101800Y1362933D01*
X-101467Y1364267D01*
X-100800Y1365433D01*
X-99800Y1366100D01*
X-98800Y1366266D01*
X-97800Y1366100D01*
X-96800Y1365433D01*
X-96133Y1364267D01*
X-95967Y1362933D01*
X-96133Y1361600D01*
X-96800Y1360433D01*
X-97800Y1359767D01*
X-98800Y1359600D01*
G01X-90333D02*
Y1366266D01*
G01Y1364600D02*
X-89667Y1365433D01*
X-88667Y1366100D01*
X-87333Y1366266D01*
X-86167Y1366100D01*
X-85167Y1365433D01*
X-84667Y1364267D01*
Y1359600D01*
G01X-64900Y1369600D02*
Y1359600D01*
G01X-68733Y1369600D02*
X-61067D01*
G01X-57100Y1359600D02*
Y1369600D01*
G01X-50100D02*
Y1359600D01*
G01Y1364600D02*
X-57100D01*
G01X-46633Y1359600D02*
Y1369600D01*
X-42300Y1361267D01*
X-37967Y1369600D01*
Y1359600D01*
G01X-34333Y1369600D02*
Y1359600D01*
X-27667D01*
G01X-5400Y1369600D02*
Y1359600D01*
G01Y1361100D02*
X-6067Y1360267D01*
X-7067Y1359767D01*
X-8233Y1359600D01*
X-9567Y1359933D01*
X-10567Y1360766D01*
X-11233Y1361767D01*
X-11400Y1362933D01*
X-11233Y1364100D01*
X-10567Y1365100D01*
X-9567Y1365933D01*
X-8233Y1366266D01*
X-7067Y1366100D01*
X-6233Y1365767D01*
X-5400Y1365100D01*
G01X400Y1364100D02*
X5733D01*
X5233Y1365267D01*
X4400Y1365933D01*
X3233Y1366266D01*
X2067Y1366100D01*
X1067Y1365600D01*
X400Y1364433D01*
X67Y1363433D01*
Y1362433D01*
X400Y1361433D01*
X1233Y1360433D01*
X2233Y1359767D01*
X3400Y1359600D01*
X4567Y1359933D01*
X5733Y1360933D01*
G01X13200Y1359600D02*
Y1368100D01*
X13533Y1368933D01*
X14200Y1369433D01*
X15200Y1369600D01*
X16200Y1369267D01*
X16700Y1368433D01*
G01X14700Y1365600D02*
X11367D01*
G01X28500Y1359600D02*
Y1366266D01*
G01Y1365100D02*
X27833Y1365767D01*
X26833Y1366100D01*
X25667Y1366266D01*
X24500Y1365933D01*
X23500Y1365267D01*
X22833Y1364267D01*
X22500Y1362933D01*
X22833Y1361600D01*
X23500Y1360600D01*
X24500Y1359933D01*
X25667Y1359600D01*
X26833Y1359767D01*
X27833Y1360267D01*
X28500Y1360933D01*
G01X33967Y1366266D02*
Y1361600D01*
X34633Y1360433D01*
X35633Y1359767D01*
X36800Y1359600D01*
X37967Y1359767D01*
X38967Y1360433D01*
X39633Y1361600D01*
G01Y1359600D02*
Y1366266D01*
G01X48100Y1359600D02*
Y1369600D01*
G01X59400D02*
Y1359600D01*
G01X57067Y1366266D02*
X61733D01*
G01X82000Y1369600D02*
Y1359600D01*
G01X79667Y1366266D02*
X84333D01*
G01X89800Y1356600D02*
X90800Y1356267D01*
X92133Y1356600D01*
X92967Y1357267D01*
X93633Y1358100D01*
X94633Y1360766D01*
X96800Y1366266D01*
G01X91467D02*
X94633Y1360766D01*
G01X101600Y1356267D02*
Y1366266D01*
G01Y1364767D02*
X102433Y1365600D01*
X103266Y1366100D01*
X104600Y1366266D01*
X105767Y1366100D01*
X106933Y1365267D01*
X107433Y1364100D01*
X107600Y1362933D01*
X107433Y1361767D01*
X106933Y1360600D01*
X105933Y1359933D01*
X104600Y1359600D01*
X103433Y1359767D01*
X102267Y1360267D01*
X101600Y1360933D01*
G01X113400Y1364100D02*
X118733D01*
X118233Y1365267D01*
X117400Y1365933D01*
X116233Y1366266D01*
X115067Y1366100D01*
X114067Y1365600D01*
X113400Y1364433D01*
X113067Y1363433D01*
Y1362433D01*
X113400Y1361433D01*
X114233Y1360433D01*
X115233Y1359767D01*
X116400Y1359600D01*
X117567Y1359933D01*
X118733Y1360933D01*
G01X-78967Y710600D02*
X-85633D01*
Y720600D01*
X-78967D01*
G01X-81633Y715767D02*
X-85633D01*
G01X-73167Y712433D02*
X-68833D01*
G01Y715433D02*
X-73167D01*
G01X-63367Y712100D02*
X-62367Y711267D01*
X-61200Y710767D01*
X-59700Y710600D01*
X-58200Y710933D01*
X-57033Y711600D01*
X-56200Y712767D01*
X-56033Y714100D01*
X-56367Y715433D01*
X-57200Y716267D01*
X-58367Y716933D01*
X-59533Y717100D01*
X-60700Y716933D01*
X-62200Y716267D01*
X-61700Y720600D01*
X-57200D01*
G01X-41433Y710600D02*
Y720600D01*
X-37100Y712267D01*
X-32767Y720600D01*
Y710600D01*
G01X-27800Y720600D02*
X-23800D01*
G01X-25800D02*
Y710600D01*
G01X-27800D02*
X-23800D01*
G01X-17833Y720600D02*
Y710600D01*
X-11167D01*
G01X-6700Y711933D02*
X-5367Y711100D01*
X-3867Y710600D01*
X-2533D01*
X-1200Y711100D01*
X-200Y711933D01*
X300Y713100D01*
X-33Y714266D01*
X-867Y715267D01*
X-2367Y715933D01*
X-4367Y716267D01*
X-5533Y716933D01*
X-6033Y718100D01*
X-5700Y719267D01*
X-4867Y720100D01*
X-3700Y720600D01*
X-2533D01*
X-1367Y720267D01*
X-367Y719433D01*
G01X18567Y707267D02*
X16900Y708933D01*
X16067Y710600D01*
Y717266D01*
X16900Y718933D01*
X18567Y720600D01*
G01X33700Y710600D02*
Y717266D01*
G01Y716100D02*
X33033Y716767D01*
X32033Y717100D01*
X30867Y717266D01*
X29700Y716933D01*
X28700Y716267D01*
X28033Y715267D01*
X27700Y713933D01*
X28033Y712600D01*
X28700Y711600D01*
X29700Y710933D01*
X30867Y710600D01*
X32033Y710767D01*
X33033Y711267D01*
X33700Y711933D01*
G01X42000Y710600D02*
Y720600D01*
G01X49133Y717266D02*
X51133Y710600D01*
X53300Y717266D01*
X55467Y710600D01*
X57467Y717266D01*
G01X67600Y710600D02*
Y717266D01*
G01Y716100D02*
X66933Y716767D01*
X65933Y717100D01*
X64767Y717266D01*
X63600Y716933D01*
X62600Y716267D01*
X61933Y715267D01*
X61600Y713933D01*
X61933Y712600D01*
X62600Y711600D01*
X63600Y710933D01*
X64767Y710600D01*
X65933Y710767D01*
X66933Y711267D01*
X67600Y711933D01*
G01X72400Y707600D02*
X73400Y707267D01*
X74733Y707600D01*
X75567Y708267D01*
X76233Y709100D01*
X77233Y711766D01*
X79400Y717266D01*
G01X74067D02*
X77233Y711766D01*
G01X84700D02*
X85533Y711100D01*
X86700Y710600D01*
X87700D01*
X88700Y710933D01*
X89367Y711433D01*
X89700Y712100D01*
X89533Y713100D01*
X88867Y713600D01*
X85866Y714600D01*
X85200Y715767D01*
X85533Y716600D01*
X86200Y717100D01*
X87200Y717266D01*
X88200Y717100D01*
X89200Y716600D01*
G01X106967Y710600D02*
Y720600D01*
G01X112300Y717266D02*
X106967Y713433D01*
G01X109133Y714933D02*
X112633Y710600D01*
G01X118600Y715100D02*
X123933D01*
X123433Y716267D01*
X122600Y716933D01*
X121433Y717266D01*
X120267Y717100D01*
X119267Y716600D01*
X118600Y715433D01*
X118267Y714433D01*
Y713433D01*
X118600Y712433D01*
X119433Y711433D01*
X120433Y710767D01*
X121600Y710600D01*
X122767Y710933D01*
X123933Y711933D01*
G01X129900Y715100D02*
X135233D01*
X134733Y716267D01*
X133900Y716933D01*
X132733Y717266D01*
X131567Y717100D01*
X130567Y716600D01*
X129900Y715433D01*
X129567Y714433D01*
Y713433D01*
X129900Y712433D01*
X130733Y711433D01*
X131733Y710767D01*
X132900Y710600D01*
X134067Y710933D01*
X135233Y711933D01*
G01X140700Y707267D02*
Y717266D01*
G01Y715767D02*
X141533Y716600D01*
X142366Y717100D01*
X143700Y717266D01*
X144867Y717100D01*
X146033Y716267D01*
X146533Y715100D01*
X146700Y713933D01*
X146533Y712767D01*
X146033Y711600D01*
X145033Y710933D01*
X143700Y710600D01*
X142533Y710767D01*
X141367Y711267D01*
X140700Y711933D01*
G01X162633Y712100D02*
X163633Y711267D01*
X164800Y710767D01*
X166300Y710600D01*
X167800Y710933D01*
X168967Y711600D01*
X169800Y712767D01*
X169967Y714100D01*
X169633Y715433D01*
X168800Y716267D01*
X167633Y716933D01*
X166467Y717100D01*
X165300Y716933D01*
X163800Y716267D01*
X164300Y720600D01*
X168800D01*
G01X183900Y710600D02*
Y717266D01*
G01Y715433D02*
X184400Y716267D01*
X185233Y716933D01*
X186400Y717266D01*
X187566Y716933D01*
X188400Y716267D01*
X188900Y715433D01*
Y710600D01*
G01Y715433D02*
X189400Y716267D01*
X190233Y716933D01*
X191400Y717266D01*
X192567Y716933D01*
X193400Y716267D01*
X193900Y715267D01*
Y710600D01*
G01X200200Y717266D02*
Y710600D01*
G01Y719933D02*
X199867Y720100D01*
Y720433D01*
X200200Y720600D01*
X200533Y720433D01*
Y720100D01*
X200200Y719933D01*
G01X211500Y710600D02*
Y720600D01*
G01X220300Y711766D02*
X221133Y711100D01*
X222300Y710600D01*
X223300D01*
X224300Y710933D01*
X224967Y711433D01*
X225300Y712100D01*
X225133Y713100D01*
X224467Y713600D01*
X221466Y714600D01*
X220800Y715767D01*
X221133Y716600D01*
X221800Y717100D01*
X222800Y717266D01*
X223800Y717100D01*
X224800Y716600D01*
G01X234933Y707267D02*
X236600Y708933D01*
X237433Y710600D01*
Y717266D01*
X236600Y718933D01*
X234933Y720600D01*
G01X-46233Y782967D02*
X-47233Y783467D01*
X-48400Y783800D01*
X-49733D01*
X-51234Y783300D01*
X-52400Y782467D01*
X-53233Y781467D01*
X-53900Y779800D01*
X-54067Y778300D01*
X-53733Y776800D01*
X-53233Y775800D01*
X-52233Y774800D01*
X-51067Y774133D01*
X-49900Y773800D01*
X-48733D01*
X-47567Y774133D01*
X-46567Y774633D01*
X-45733Y775300D01*
G01X-54367Y971400D02*
X-50200Y981400D01*
X-46033Y971400D01*
G01X-47533Y974900D02*
X-52867D01*
G01X-22810Y1290280D02*
X-19477D01*
Y1287280D01*
X-20477Y1286280D01*
X-21643Y1285613D01*
X-23310Y1285280D01*
X-24977Y1285613D01*
X-26143Y1286280D01*
X-27143Y1287280D01*
X-27810Y1288447D01*
X-28143Y1289780D01*
Y1290947D01*
X-27810Y1291946D01*
X-27143Y1293113D01*
X-26143Y1294113D01*
X-25144Y1294780D01*
X-23810Y1295280D01*
X-22643D01*
X-21310Y1294947D01*
X-20310Y1294280D01*
G01X-9510Y1285280D02*
Y1291946D01*
G01Y1290780D02*
X-10177Y1291447D01*
X-11177Y1291780D01*
X-12343Y1291946D01*
X-13510Y1291613D01*
X-14510Y1290947D01*
X-15177Y1289947D01*
X-15510Y1288613D01*
X-15177Y1287280D01*
X-14510Y1286280D01*
X-13510Y1285613D01*
X-12343Y1285280D01*
X-11177Y1285447D01*
X-10177Y1285947D01*
X-9510Y1286613D01*
G01X-4210Y1281947D02*
Y1291946D01*
G01Y1290447D02*
X-3377Y1291280D01*
X-2544Y1291780D01*
X-1210Y1291946D01*
X-43Y1291780D01*
X1123Y1290947D01*
X1623Y1289780D01*
X1790Y1288613D01*
X1623Y1287447D01*
X1123Y1286280D01*
X123Y1285613D01*
X-1210Y1285280D01*
X-2377Y1285447D01*
X-3543Y1285947D01*
X-4210Y1286613D01*
G01X16390Y1295280D02*
X18723Y1285280D01*
X21390Y1295280D01*
X24057Y1285280D01*
X26390Y1295280D01*
G01X32690Y1291946D02*
Y1285280D01*
G01Y1294613D02*
X32357Y1294780D01*
Y1295113D01*
X32690Y1295280D01*
X33023Y1295113D01*
Y1294780D01*
X32690Y1294613D01*
G01X46990Y1295280D02*
Y1285280D01*
G01Y1286780D02*
X46323Y1285947D01*
X45323Y1285447D01*
X44157Y1285280D01*
X42823Y1285613D01*
X41823Y1286446D01*
X41157Y1287447D01*
X40990Y1288613D01*
X41157Y1289780D01*
X41823Y1290780D01*
X42823Y1291613D01*
X44157Y1291946D01*
X45323Y1291780D01*
X46157Y1291447D01*
X46990Y1290780D01*
G01X55290Y1295280D02*
Y1285280D01*
G01X52957Y1291946D02*
X57623D01*
G01X63757Y1285280D02*
Y1295280D01*
G01Y1290447D02*
X64590Y1291280D01*
X65423Y1291780D01*
X66757Y1291946D01*
X67757Y1291780D01*
X68923Y1291113D01*
X69423Y1290113D01*
Y1285280D01*
G01X-20370Y1333880D02*
X-21704Y1334047D01*
X-22870Y1334713D01*
X-23870Y1335713D01*
X-24537Y1336880D01*
X-24870Y1338213D01*
Y1339547D01*
X-24537Y1340880D01*
X-23870Y1342047D01*
X-22870Y1343047D01*
X-21704Y1343713D01*
X-20370Y1343880D01*
X-19037Y1343713D01*
X-17870Y1343047D01*
X-16870Y1342047D01*
X-16203Y1340880D01*
X-15870Y1339547D01*
Y1338213D01*
X-16203Y1336880D01*
X-16870Y1335713D01*
X-17870Y1334713D01*
X-19037Y1334047D01*
X-20370Y1333880D01*
G01X-11903Y1340546D02*
Y1335880D01*
X-11237Y1334713D01*
X-10237Y1334047D01*
X-9070Y1333880D01*
X-7903Y1334047D01*
X-6903Y1334713D01*
X-6237Y1335880D01*
G01Y1333880D02*
Y1340546D01*
G01X2230Y1343880D02*
Y1333880D01*
G01X-103Y1340546D02*
X4563D01*
G01X11030Y1338380D02*
X16363D01*
X15863Y1339547D01*
X15030Y1340213D01*
X13863Y1340546D01*
X12697Y1340380D01*
X11697Y1339880D01*
X11030Y1338713D01*
X10697Y1337713D01*
Y1336713D01*
X11030Y1335713D01*
X11863Y1334713D01*
X12863Y1334047D01*
X14030Y1333880D01*
X15197Y1334213D01*
X16363Y1335213D01*
G01X22497Y1333880D02*
Y1340546D01*
G01Y1339213D02*
X23330Y1339880D01*
X24163Y1340380D01*
X25330Y1340546D01*
X26163Y1340380D01*
X27163Y1339880D01*
G01X43763Y1333880D02*
Y1343880D01*
X47097D01*
X48430Y1343380D01*
X49430Y1342713D01*
X50263Y1341713D01*
X50930Y1340546D01*
X51097Y1338880D01*
X50930Y1337213D01*
X50263Y1336047D01*
X49430Y1335046D01*
X48430Y1334380D01*
X47097Y1333880D01*
X43763D01*
G01X58730Y1340546D02*
Y1333880D01*
G01Y1343213D02*
X58397Y1343380D01*
Y1343713D01*
X58730Y1343880D01*
X59063Y1343713D01*
Y1343380D01*
X58730Y1343213D01*
G01X73030Y1333880D02*
Y1340546D01*
G01Y1339380D02*
X72363Y1340047D01*
X71363Y1340380D01*
X70197Y1340546D01*
X69030Y1340213D01*
X68030Y1339547D01*
X67363Y1338547D01*
X67030Y1337213D01*
X67363Y1335880D01*
X68030Y1334880D01*
X69030Y1334213D01*
X70197Y1333880D01*
X71363Y1334047D01*
X72363Y1334547D01*
X73030Y1335213D01*
G01X76330Y1333880D02*
Y1340546D01*
G01Y1338713D02*
X76830Y1339547D01*
X77663Y1340213D01*
X78830Y1340546D01*
X79996Y1340213D01*
X80830Y1339547D01*
X81330Y1338713D01*
Y1333880D01*
G01Y1338713D02*
X81830Y1339547D01*
X82663Y1340213D01*
X83830Y1340546D01*
X84997Y1340213D01*
X85830Y1339547D01*
X86330Y1338547D01*
Y1333880D01*
G01X90130Y1338380D02*
X95463D01*
X94963Y1339547D01*
X94130Y1340213D01*
X92963Y1340546D01*
X91797Y1340380D01*
X90797Y1339880D01*
X90130Y1338713D01*
X89797Y1337713D01*
Y1336713D01*
X90130Y1335713D01*
X90963Y1334713D01*
X91963Y1334047D01*
X93130Y1333880D01*
X94297Y1334213D01*
X95463Y1335213D01*
G01X103930Y1343880D02*
Y1333880D01*
G01X101597Y1340546D02*
X106263D01*
G01X112730Y1338380D02*
X118063D01*
X117563Y1339547D01*
X116730Y1340213D01*
X115563Y1340546D01*
X114397Y1340380D01*
X113397Y1339880D01*
X112730Y1338713D01*
X112397Y1337713D01*
Y1336713D01*
X112730Y1335713D01*
X113563Y1334713D01*
X114563Y1334047D01*
X115730Y1333880D01*
X116897Y1334213D01*
X118063Y1335213D01*
G01X124197Y1333880D02*
Y1340546D01*
G01Y1339213D02*
X125030Y1339880D01*
X125863Y1340380D01*
X127030Y1340546D01*
X127863Y1340380D01*
X128863Y1339880D01*
G01X18733Y885133D02*
X19400Y885633D01*
X19900Y886466D01*
X20233Y887633D01*
X19900Y888633D01*
X19233Y889300D01*
X18067Y889800D01*
X13567D01*
Y879800D01*
X19067D01*
X20233Y880467D01*
X20900Y881467D01*
X21233Y882633D01*
X20900Y883800D01*
X19900Y884800D01*
X18733Y885133D01*
X13567D01*
G01X47700Y1150600D02*
X51033D01*
Y1147600D01*
X50033Y1146600D01*
X48867Y1145933D01*
X47200Y1145600D01*
X45533Y1145933D01*
X44367Y1146600D01*
X43367Y1147600D01*
X42700Y1148767D01*
X42367Y1150100D01*
Y1151267D01*
X42700Y1152266D01*
X43367Y1153433D01*
X44367Y1154433D01*
X45366Y1155100D01*
X46700Y1155600D01*
X47867D01*
X49200Y1155267D01*
X50200Y1154600D01*
G01X61000Y1145600D02*
Y1152266D01*
G01Y1151100D02*
X60333Y1151767D01*
X59333Y1152100D01*
X58167Y1152266D01*
X57000Y1151933D01*
X56000Y1151267D01*
X55333Y1150267D01*
X55000Y1148933D01*
X55333Y1147600D01*
X56000Y1146600D01*
X57000Y1145933D01*
X58167Y1145600D01*
X59333Y1145767D01*
X60333Y1146267D01*
X61000Y1146933D01*
G01X66300Y1142267D02*
Y1152266D01*
G01Y1150767D02*
X67133Y1151600D01*
X67966Y1152100D01*
X69300Y1152266D01*
X70467Y1152100D01*
X71633Y1151267D01*
X72133Y1150100D01*
X72300Y1148933D01*
X72133Y1147767D01*
X71633Y1146600D01*
X70633Y1145933D01*
X69300Y1145600D01*
X68133Y1145767D01*
X66967Y1146267D01*
X66300Y1146933D01*
G01X86900Y1155600D02*
X89233Y1145600D01*
X91900Y1155600D01*
X94567Y1145600D01*
X96900Y1155600D01*
G01X103200Y1152266D02*
Y1145600D01*
G01Y1154933D02*
X102867Y1155100D01*
Y1155433D01*
X103200Y1155600D01*
X103533Y1155433D01*
Y1155100D01*
X103200Y1154933D01*
G01X117500Y1155600D02*
Y1145600D01*
G01Y1147100D02*
X116833Y1146267D01*
X115833Y1145767D01*
X114667Y1145600D01*
X113333Y1145933D01*
X112333Y1146766D01*
X111667Y1147767D01*
X111500Y1148933D01*
X111667Y1150100D01*
X112333Y1151100D01*
X113333Y1151933D01*
X114667Y1152266D01*
X115833Y1152100D01*
X116667Y1151767D01*
X117500Y1151100D01*
G01X125800Y1155600D02*
Y1145600D01*
G01X123467Y1152266D02*
X128133D01*
G01X134267Y1145600D02*
Y1155600D01*
G01Y1150767D02*
X135100Y1151600D01*
X135933Y1152100D01*
X137267Y1152266D01*
X138267Y1152100D01*
X139433Y1151433D01*
X139933Y1150433D01*
Y1145600D01*
G01X146233Y1147433D02*
X150567D01*
G01Y1150433D02*
X146233D01*
G01X156033Y1147600D02*
X157033Y1146433D01*
X158366Y1145767D01*
X159867Y1145600D01*
X161200Y1145767D01*
X162533Y1146600D01*
X163367Y1147600D01*
X163533Y1148600D01*
X163200Y1149766D01*
X162033Y1150600D01*
X160867Y1150933D01*
X159367D01*
G01X160867D02*
X161867Y1151433D01*
X162700Y1152266D01*
X163033Y1153267D01*
X162700Y1154267D01*
X161867Y1155100D01*
X160367Y1155600D01*
X158867Y1155433D01*
X157367Y1154767D01*
G01X171000Y1155600D02*
X169666Y1155267D01*
X168667Y1154433D01*
X168000Y1153433D01*
X167500Y1152100D01*
X167333Y1150600D01*
X167500Y1149100D01*
X168000Y1147767D01*
X168667Y1146766D01*
X169666Y1145933D01*
X171000Y1145600D01*
X172333Y1145933D01*
X173333Y1146766D01*
X174000Y1147767D01*
X174500Y1149100D01*
X174667Y1150600D01*
X174500Y1152100D01*
X174000Y1153433D01*
X173333Y1154433D01*
X172333Y1155267D01*
X171000Y1155600D01*
G01X44867Y1161600D02*
Y1171600D01*
X52533Y1161600D01*
Y1171600D01*
G01X57167Y1168266D02*
Y1163600D01*
X57833Y1162433D01*
X58833Y1161767D01*
X60000Y1161600D01*
X61167Y1161767D01*
X62167Y1162433D01*
X62833Y1163600D01*
G01Y1161600D02*
Y1168266D01*
G01X66300Y1161600D02*
Y1168266D01*
G01Y1166433D02*
X66800Y1167267D01*
X67633Y1167933D01*
X68800Y1168266D01*
X69966Y1167933D01*
X70800Y1167267D01*
X71300Y1166433D01*
Y1161600D01*
G01Y1166433D02*
X71800Y1167267D01*
X72633Y1167933D01*
X73800Y1168266D01*
X74967Y1167933D01*
X75800Y1167267D01*
X76300Y1166267D01*
Y1161600D01*
G01X90400Y1162933D02*
X91733Y1162100D01*
X93233Y1161600D01*
X94567D01*
X95900Y1162100D01*
X96900Y1162933D01*
X97400Y1164100D01*
X97067Y1165266D01*
X96233Y1166267D01*
X94733Y1166933D01*
X92733Y1167267D01*
X91567Y1167933D01*
X91067Y1169100D01*
X91400Y1170267D01*
X92233Y1171100D01*
X93400Y1171600D01*
X94567D01*
X95733Y1171267D01*
X96733Y1170433D01*
G01X102200Y1158267D02*
Y1168266D01*
G01Y1166767D02*
X103033Y1167600D01*
X103866Y1168100D01*
X105200Y1168266D01*
X106367Y1168100D01*
X107533Y1167267D01*
X108033Y1166100D01*
X108200Y1164933D01*
X108033Y1163767D01*
X107533Y1162600D01*
X106533Y1161933D01*
X105200Y1161600D01*
X104033Y1161767D01*
X102867Y1162267D01*
X102200Y1162933D01*
G01X116500Y1161600D02*
X115500Y1161767D01*
X114500Y1162433D01*
X113833Y1163600D01*
X113500Y1164933D01*
X113833Y1166267D01*
X114500Y1167433D01*
X115500Y1168100D01*
X116500Y1168266D01*
X117500Y1168100D01*
X118500Y1167433D01*
X119167Y1166267D01*
X119333Y1164933D01*
X119167Y1163600D01*
X118500Y1162433D01*
X117500Y1161767D01*
X116500Y1161600D01*
G01X124967D02*
Y1171600D01*
G01X130300Y1168266D02*
X124967Y1164433D01*
G01X127133Y1165933D02*
X130633Y1161600D01*
G01X136600Y1166100D02*
X141933D01*
X141433Y1167267D01*
X140600Y1167933D01*
X139433Y1168266D01*
X138267Y1168100D01*
X137267Y1167600D01*
X136600Y1166433D01*
X136267Y1165433D01*
Y1164433D01*
X136600Y1163433D01*
X137433Y1162433D01*
X138433Y1161767D01*
X139600Y1161600D01*
X140767Y1161933D01*
X141933Y1162933D01*
G01X147900Y1162766D02*
X148733Y1162100D01*
X149900Y1161600D01*
X150900D01*
X151900Y1161933D01*
X152567Y1162433D01*
X152900Y1163100D01*
X152733Y1164100D01*
X152067Y1164600D01*
X149066Y1165600D01*
X148400Y1166767D01*
X148733Y1167600D01*
X149400Y1168100D01*
X150400Y1168266D01*
X151400Y1168100D01*
X152400Y1167600D01*
G01X159533Y1163433D02*
X163867D01*
G01Y1166433D02*
X159533D01*
G01X175000Y1161600D02*
Y1171600D01*
X168833Y1164433D01*
X177167D01*
G01X46700Y1181600D02*
X45366Y1181767D01*
X44200Y1182433D01*
X43200Y1183433D01*
X42533Y1184600D01*
X42200Y1185933D01*
Y1187267D01*
X42533Y1188600D01*
X43200Y1189767D01*
X44200Y1190767D01*
X45366Y1191433D01*
X46700Y1191600D01*
X48033Y1191433D01*
X49200Y1190767D01*
X50200Y1189767D01*
X50867Y1188600D01*
X51200Y1187267D01*
Y1185933D01*
X50867Y1184600D01*
X50200Y1183433D01*
X49200Y1182433D01*
X48033Y1181767D01*
X46700Y1181600D01*
G01X55167Y1188266D02*
Y1183600D01*
X55833Y1182433D01*
X56833Y1181767D01*
X58000Y1181600D01*
X59167Y1181767D01*
X60167Y1182433D01*
X60833Y1183600D01*
G01Y1181600D02*
Y1188266D01*
G01X69300Y1191600D02*
Y1181600D01*
G01X66967Y1188266D02*
X71633D01*
G01X78100Y1186100D02*
X83433D01*
X82933Y1187267D01*
X82100Y1187933D01*
X80933Y1188266D01*
X79767Y1188100D01*
X78767Y1187600D01*
X78100Y1186433D01*
X77767Y1185433D01*
Y1184433D01*
X78100Y1183433D01*
X78933Y1182433D01*
X79933Y1181767D01*
X81100Y1181600D01*
X82267Y1181933D01*
X83433Y1182933D01*
G01X89567Y1181600D02*
Y1188266D01*
G01Y1186933D02*
X90400Y1187600D01*
X91233Y1188100D01*
X92400Y1188266D01*
X93233Y1188100D01*
X94233Y1187600D01*
G01X110833Y1181600D02*
Y1191600D01*
X114167D01*
X115500Y1191100D01*
X116500Y1190433D01*
X117333Y1189433D01*
X118000Y1188266D01*
X118167Y1186600D01*
X118000Y1184933D01*
X117333Y1183767D01*
X116500Y1182766D01*
X115500Y1182100D01*
X114167Y1181600D01*
X110833D01*
G01X125800Y1188266D02*
Y1181600D01*
G01Y1190933D02*
X125467Y1191100D01*
Y1191433D01*
X125800Y1191600D01*
X126133Y1191433D01*
Y1191100D01*
X125800Y1190933D01*
G01X140100Y1181600D02*
Y1188266D01*
G01Y1187100D02*
X139433Y1187767D01*
X138433Y1188100D01*
X137267Y1188266D01*
X136100Y1187933D01*
X135100Y1187267D01*
X134433Y1186267D01*
X134100Y1184933D01*
X134433Y1183600D01*
X135100Y1182600D01*
X136100Y1181933D01*
X137267Y1181600D01*
X138433Y1181767D01*
X139433Y1182267D01*
X140100Y1182933D01*
G01X143400Y1181600D02*
Y1188266D01*
G01Y1186433D02*
X143900Y1187267D01*
X144733Y1187933D01*
X145900Y1188266D01*
X147066Y1187933D01*
X147900Y1187267D01*
X148400Y1186433D01*
Y1181600D01*
G01Y1186433D02*
X148900Y1187267D01*
X149733Y1187933D01*
X150900Y1188266D01*
X152067Y1187933D01*
X152900Y1187267D01*
X153400Y1186267D01*
Y1181600D01*
G01X157200Y1186100D02*
X162533D01*
X162033Y1187267D01*
X161200Y1187933D01*
X160033Y1188266D01*
X158867Y1188100D01*
X157867Y1187600D01*
X157200Y1186433D01*
X156867Y1185433D01*
Y1184433D01*
X157200Y1183433D01*
X158033Y1182433D01*
X159033Y1181767D01*
X160200Y1181600D01*
X161367Y1181933D01*
X162533Y1182933D01*
G01X171000Y1191600D02*
Y1181600D01*
G01X168667Y1188266D02*
X173333D01*
G01X179800Y1186100D02*
X185133D01*
X184633Y1187267D01*
X183800Y1187933D01*
X182633Y1188266D01*
X181467Y1188100D01*
X180467Y1187600D01*
X179800Y1186433D01*
X179467Y1185433D01*
Y1184433D01*
X179800Y1183433D01*
X180633Y1182433D01*
X181633Y1181767D01*
X182800Y1181600D01*
X183967Y1181933D01*
X185133Y1182933D01*
G01X191267Y1181600D02*
Y1188266D01*
G01Y1186933D02*
X192100Y1187600D01*
X192933Y1188100D01*
X194100Y1188266D01*
X194933Y1188100D01*
X195933Y1187600D01*
G01X202733Y1183433D02*
X207067D01*
G01Y1186433D02*
X202733D01*
G01X216200Y1181600D02*
Y1191600D01*
X214200Y1189600D01*
G01Y1181600D02*
X218200D01*
G01X227500Y1191600D02*
X226166Y1191267D01*
X225167Y1190433D01*
X224500Y1189433D01*
X224000Y1188100D01*
X223833Y1186600D01*
X224000Y1185100D01*
X224500Y1183767D01*
X225167Y1182766D01*
X226166Y1181933D01*
X227500Y1181600D01*
X228833Y1181933D01*
X229833Y1182766D01*
X230500Y1183767D01*
X231000Y1185100D01*
X231167Y1186600D01*
X231000Y1188100D01*
X230500Y1189433D01*
X229833Y1190433D01*
X228833Y1191267D01*
X227500Y1191600D01*
G01X235133Y1183600D02*
X236133Y1182433D01*
X237466Y1181767D01*
X238967Y1181600D01*
X240300Y1181767D01*
X241633Y1182600D01*
X242467Y1183600D01*
X242633Y1184600D01*
X242300Y1185766D01*
X241133Y1186600D01*
X239967Y1186933D01*
X238467D01*
G01X239967D02*
X240967Y1187433D01*
X241800Y1188266D01*
X242133Y1189267D01*
X241800Y1190267D01*
X240967Y1191100D01*
X239467Y1191600D01*
X237967Y1191433D01*
X236467Y1190767D01*
G01X42700Y1213600D02*
X46700D01*
G01X44700D02*
Y1203600D01*
G01X42700D02*
X46700D01*
G01X53167D02*
Y1210266D01*
G01Y1208600D02*
X53833Y1209433D01*
X54833Y1210100D01*
X56167Y1210266D01*
X57333Y1210100D01*
X58333Y1209433D01*
X58833Y1208267D01*
Y1203600D01*
G01X64467D02*
Y1210266D01*
G01Y1208600D02*
X65133Y1209433D01*
X66133Y1210100D01*
X67467Y1210266D01*
X68633Y1210100D01*
X69633Y1209433D01*
X70133Y1208267D01*
Y1203600D01*
G01X76100Y1208100D02*
X81433D01*
X80933Y1209267D01*
X80100Y1209933D01*
X78933Y1210266D01*
X77767Y1210100D01*
X76767Y1209600D01*
X76100Y1208433D01*
X75767Y1207433D01*
Y1206433D01*
X76100Y1205433D01*
X76933Y1204433D01*
X77933Y1203767D01*
X79100Y1203600D01*
X80267Y1203933D01*
X81433Y1204933D01*
G01X87567Y1203600D02*
Y1210266D01*
G01Y1208933D02*
X88400Y1209600D01*
X89233Y1210100D01*
X90400Y1210266D01*
X91233Y1210100D01*
X92233Y1209600D01*
G01X108833Y1203600D02*
Y1213600D01*
X112167D01*
X113500Y1213100D01*
X114500Y1212433D01*
X115333Y1211433D01*
X116000Y1210266D01*
X116167Y1208600D01*
X116000Y1206933D01*
X115333Y1205767D01*
X114500Y1204766D01*
X113500Y1204100D01*
X112167Y1203600D01*
X108833D01*
G01X123800Y1210266D02*
Y1203600D01*
G01Y1212933D02*
X123467Y1213100D01*
Y1213433D01*
X123800Y1213600D01*
X124133Y1213433D01*
Y1213100D01*
X123800Y1212933D01*
G01X138100Y1203600D02*
Y1210266D01*
G01Y1209100D02*
X137433Y1209767D01*
X136433Y1210100D01*
X135267Y1210266D01*
X134100Y1209933D01*
X133100Y1209267D01*
X132433Y1208267D01*
X132100Y1206933D01*
X132433Y1205600D01*
X133100Y1204600D01*
X134100Y1203933D01*
X135267Y1203600D01*
X136433Y1203767D01*
X137433Y1204267D01*
X138100Y1204933D01*
G01X141400Y1203600D02*
Y1210266D01*
G01Y1208433D02*
X141900Y1209267D01*
X142733Y1209933D01*
X143900Y1210266D01*
X145066Y1209933D01*
X145900Y1209267D01*
X146400Y1208433D01*
Y1203600D01*
G01Y1208433D02*
X146900Y1209267D01*
X147733Y1209933D01*
X148900Y1210266D01*
X150067Y1209933D01*
X150900Y1209267D01*
X151400Y1208267D01*
Y1203600D01*
G01X155200Y1208100D02*
X160533D01*
X160033Y1209267D01*
X159200Y1209933D01*
X158033Y1210266D01*
X156867Y1210100D01*
X155867Y1209600D01*
X155200Y1208433D01*
X154867Y1207433D01*
Y1206433D01*
X155200Y1205433D01*
X156033Y1204433D01*
X157033Y1203767D01*
X158200Y1203600D01*
X159367Y1203933D01*
X160533Y1204933D01*
G01X169000Y1213600D02*
Y1203600D01*
G01X166667Y1210266D02*
X171333D01*
G01X177800Y1208100D02*
X183133D01*
X182633Y1209267D01*
X181800Y1209933D01*
X180633Y1210266D01*
X179467Y1210100D01*
X178467Y1209600D01*
X177800Y1208433D01*
X177467Y1207433D01*
Y1206433D01*
X177800Y1205433D01*
X178633Y1204433D01*
X179633Y1203767D01*
X180800Y1203600D01*
X181967Y1203933D01*
X183133Y1204933D01*
G01X189267Y1203600D02*
Y1210266D01*
G01Y1208933D02*
X190100Y1209600D01*
X190933Y1210100D01*
X192100Y1210266D01*
X192933Y1210100D01*
X193933Y1209600D01*
G01X200733Y1205433D02*
X205067D01*
G01Y1208433D02*
X200733D01*
G01X211367Y1204766D02*
X212533Y1203933D01*
X213867Y1203600D01*
X215200Y1203933D01*
X216367Y1204933D01*
X217200Y1206433D01*
X217533Y1207933D01*
Y1209767D01*
X217200Y1211267D01*
X216367Y1212600D01*
X215367Y1213267D01*
X214200Y1213600D01*
X212866Y1213267D01*
X211867Y1212600D01*
X211200Y1211600D01*
X210867Y1210266D01*
X211200Y1209100D01*
X212033Y1207933D01*
X213033Y1207266D01*
X214200Y1207100D01*
X215533Y1207433D01*
X216533Y1208267D01*
X217533Y1209767D01*
G01X221833Y1205600D02*
X222833Y1204433D01*
X224166Y1203767D01*
X225667Y1203600D01*
X227000Y1203767D01*
X228333Y1204600D01*
X229167Y1205600D01*
X229333Y1206600D01*
X229000Y1207766D01*
X227833Y1208600D01*
X226667Y1208933D01*
X225167D01*
G01X226667D02*
X227667Y1209433D01*
X228500Y1210266D01*
X228833Y1211267D01*
X228500Y1212267D01*
X227667Y1213100D01*
X226167Y1213600D01*
X224667Y1213433D01*
X223167Y1212767D01*
G54D12*
G01X355441Y659700D02*
Y667275D01*
X359040D01*
G01X357714Y663614D02*
X355441D01*
G01X364815Y659700D02*
X364247Y659826D01*
X363679Y660331D01*
X363300Y661215D01*
X363111Y662225D01*
X363300Y663235D01*
X363679Y664119D01*
X364247Y664624D01*
X364815Y664750D01*
X365384Y664624D01*
X365952Y664119D01*
X366330Y663235D01*
X366425Y662225D01*
X366330Y661215D01*
X365952Y660331D01*
X365384Y659826D01*
X364815Y659700D01*
G01X371065D02*
Y664750D01*
G01Y663740D02*
X371538Y664245D01*
X372012Y664624D01*
X372675Y664750D01*
X373148Y664624D01*
X373716Y664245D01*
G01X386120Y663109D02*
X389150D01*
X388866Y663993D01*
X388393Y664497D01*
X387730Y664750D01*
X387067Y664624D01*
X386499Y664245D01*
X386120Y663361D01*
X385931Y662604D01*
Y661846D01*
X386120Y661089D01*
X386594Y660331D01*
X387162Y659826D01*
X387825Y659700D01*
X388487Y659952D01*
X389150Y660710D01*
G01X393695Y664750D02*
X396536Y659700D01*
G01Y664750D02*
X393695Y659700D01*
G01X404395D02*
Y664750D01*
G01Y663866D02*
X404016Y664371D01*
X403448Y664624D01*
X402785Y664750D01*
X402122Y664497D01*
X401554Y663993D01*
X401175Y663235D01*
X400986Y662225D01*
X401175Y661215D01*
X401554Y660457D01*
X402122Y659952D01*
X402785Y659700D01*
X403448Y659826D01*
X404016Y660205D01*
X404395Y660710D01*
G01X407425Y659700D02*
Y664750D01*
G01Y663361D02*
X407709Y663993D01*
X408182Y664497D01*
X408845Y664750D01*
X409508Y664497D01*
X409981Y663993D01*
X410265Y663361D01*
Y659700D01*
G01Y663361D02*
X410550Y663993D01*
X411023Y664497D01*
X411686Y664750D01*
X412349Y664497D01*
X412822Y663993D01*
X413106Y663235D01*
Y659700D01*
G01X416136Y657175D02*
Y664750D01*
G01Y663614D02*
X416610Y664245D01*
X417083Y664624D01*
X417840Y664750D01*
X418503Y664624D01*
X419166Y663993D01*
X419450Y663109D01*
X419545Y662225D01*
X419450Y661341D01*
X419166Y660457D01*
X418598Y659952D01*
X417840Y659700D01*
X417178Y659826D01*
X416515Y660205D01*
X416136Y660710D01*
G01X425415Y659700D02*
Y667275D01*
G01X431570Y663109D02*
X434600D01*
X434316Y663993D01*
X433843Y664497D01*
X433180Y664750D01*
X432517Y664624D01*
X431949Y664245D01*
X431570Y663361D01*
X431381Y662604D01*
Y661846D01*
X431570Y661089D01*
X432044Y660331D01*
X432612Y659826D01*
X433275Y659700D01*
X433937Y659952D01*
X434600Y660710D01*
G01X440565Y659448D02*
X440376Y659574D01*
Y659826D01*
X440565Y659952D01*
X440755Y659826D01*
Y659574D01*
X440565Y659448D01*
G01Y662856D02*
X440376Y662982D01*
Y663235D01*
X440565Y663361D01*
X440755Y663235D01*
Y662982D01*
X440565Y662856D01*
G01X453727Y659700D02*
Y667275D01*
G01X457704D02*
Y659700D01*
G01Y663487D02*
X453727D01*
G01X463290Y659700D02*
X462722Y659826D01*
X462154Y660331D01*
X461775Y661215D01*
X461586Y662225D01*
X461775Y663235D01*
X462154Y664119D01*
X462722Y664624D01*
X463290Y664750D01*
X463859Y664624D01*
X464427Y664119D01*
X464805Y663235D01*
X464900Y662225D01*
X464805Y661215D01*
X464427Y660331D01*
X463859Y659826D01*
X463290Y659700D01*
G01X470865D02*
Y667275D01*
G01X477020Y663109D02*
X480050D01*
X479766Y663993D01*
X479293Y664497D01*
X478630Y664750D01*
X477967Y664624D01*
X477399Y664245D01*
X477020Y663361D01*
X476831Y662604D01*
Y661846D01*
X477020Y661089D01*
X477494Y660331D01*
X478062Y659826D01*
X478725Y659700D01*
X479387Y659952D01*
X480050Y660710D01*
G01X491507Y659700D02*
Y667275D01*
X493401D01*
X494159Y666896D01*
X494727Y666391D01*
X495200Y665634D01*
X495579Y664750D01*
X495674Y663487D01*
X495579Y662225D01*
X495200Y661341D01*
X494727Y660584D01*
X494159Y660079D01*
X493401Y659700D01*
X491507D01*
G01X501165Y664750D02*
Y659700D01*
G01Y666770D02*
X500976Y666896D01*
Y667149D01*
X501165Y667275D01*
X501355Y667149D01*
Y666896D01*
X501165Y666770D01*
G01X510445Y659700D02*
Y664750D01*
G01Y663866D02*
X510066Y664371D01*
X509498Y664624D01*
X508835Y664750D01*
X508172Y664497D01*
X507604Y663993D01*
X507225Y663235D01*
X507036Y662225D01*
X507225Y661215D01*
X507604Y660457D01*
X508172Y659952D01*
X508835Y659700D01*
X509498Y659826D01*
X510066Y660205D01*
X510445Y660710D01*
G01X516315Y659448D02*
X516126Y659574D01*
Y659826D01*
X516315Y659952D01*
X516505Y659826D01*
Y659574D01*
X516315Y659448D01*
G01X521807Y661215D02*
X522375Y660331D01*
X523133Y659826D01*
X523985Y659700D01*
X524743Y659826D01*
X525500Y660457D01*
X525974Y661215D01*
X526068Y661972D01*
X525879Y662856D01*
X525216Y663487D01*
X524553Y663740D01*
X523701D01*
G01X524553D02*
X525121Y664119D01*
X525595Y664750D01*
X525784Y665507D01*
X525595Y666265D01*
X525121Y666896D01*
X524269Y667275D01*
X523417Y667149D01*
X522565Y666644D01*
G01X531465Y659448D02*
X531276Y659574D01*
Y659826D01*
X531465Y659952D01*
X531655Y659826D01*
Y659574D01*
X531465Y659448D01*
G01X539040Y659700D02*
Y667275D01*
X537904Y665760D01*
G01Y659700D02*
X540177D01*
G01X546615D02*
X547278Y659826D01*
X548036Y660205D01*
X548509Y660836D01*
X548699Y661720D01*
X548509Y662604D01*
X547941Y663361D01*
X547089Y663740D01*
X546142D01*
X545574Y663993D01*
X545100Y664624D01*
X544911Y665507D01*
X545195Y666391D01*
X545858Y667023D01*
X546615Y667275D01*
X547373Y667023D01*
X548036Y666391D01*
X548320Y665507D01*
X548130Y664624D01*
X547657Y663993D01*
X547089Y663740D01*
X546142D01*
X545290Y663361D01*
X544722Y662604D01*
X544532Y661720D01*
X544722Y660836D01*
X545195Y660205D01*
X545953Y659826D01*
X546615Y659700D01*
G01X551350D02*
Y664750D01*
G01Y663361D02*
X551634Y663993D01*
X552107Y664497D01*
X552770Y664750D01*
X553433Y664497D01*
X553906Y663993D01*
X554190Y663361D01*
Y659700D01*
G01Y663361D02*
X554475Y663993D01*
X554948Y664497D01*
X555611Y664750D01*
X556274Y664497D01*
X556747Y663993D01*
X557031Y663235D01*
Y659700D01*
G01X558925D02*
Y664750D01*
G01Y663361D02*
X559209Y663993D01*
X559682Y664497D01*
X560345Y664750D01*
X561008Y664497D01*
X561481Y663993D01*
X561765Y663361D01*
Y659700D01*
G01Y663361D02*
X562050Y663993D01*
X562523Y664497D01*
X563186Y664750D01*
X563849Y664497D01*
X564322Y663993D01*
X564606Y663235D01*
Y659700D01*
G01X576915Y664750D02*
Y659700D01*
G01Y666770D02*
X576726Y666896D01*
Y667149D01*
X576915Y667275D01*
X577105Y667149D01*
Y666896D01*
X576915Y666770D01*
G01X583070Y660584D02*
X583544Y660079D01*
X584206Y659700D01*
X584775D01*
X585343Y659952D01*
X585721Y660331D01*
X585911Y660836D01*
X585816Y661594D01*
X585437Y661972D01*
X583733Y662730D01*
X583354Y663614D01*
X583544Y664245D01*
X583922Y664624D01*
X584490Y664750D01*
X585059Y664624D01*
X585627Y664245D01*
G01X596800Y659700D02*
Y664750D01*
G01Y663361D02*
X597084Y663993D01*
X597557Y664497D01*
X598220Y664750D01*
X598883Y664497D01*
X599356Y663993D01*
X599640Y663361D01*
Y659700D01*
G01Y663361D02*
X599925Y663993D01*
X600398Y664497D01*
X601061Y664750D01*
X601724Y664497D01*
X602197Y663993D01*
X602481Y663235D01*
Y659700D01*
G01X608920D02*
Y664750D01*
G01Y663866D02*
X608541Y664371D01*
X607973Y664624D01*
X607310Y664750D01*
X606647Y664497D01*
X606079Y663993D01*
X605700Y663235D01*
X605511Y662225D01*
X605700Y661215D01*
X606079Y660457D01*
X606647Y659952D01*
X607310Y659700D01*
X607973Y659826D01*
X608541Y660205D01*
X608920Y660710D01*
G01X613465Y659700D02*
Y664750D01*
G01Y663740D02*
X613938Y664245D01*
X614412Y664624D01*
X615075Y664750D01*
X615548Y664624D01*
X616116Y664245D01*
G01X620756Y659700D02*
Y667275D01*
G01X623786Y664750D02*
X620756Y661846D01*
G01X621987Y662982D02*
X623975Y659700D01*
G01X628520Y663109D02*
X631550D01*
X631266Y663993D01*
X630793Y664497D01*
X630130Y664750D01*
X629467Y664624D01*
X628899Y664245D01*
X628520Y663361D01*
X628331Y662604D01*
Y661846D01*
X628520Y661089D01*
X628994Y660331D01*
X629562Y659826D01*
X630225Y659700D01*
X630887Y659952D01*
X631550Y660710D01*
G01X639220Y667275D02*
Y659700D01*
G01Y660836D02*
X638841Y660205D01*
X638273Y659826D01*
X637610Y659700D01*
X636853Y659952D01*
X636285Y660584D01*
X635906Y661341D01*
X635811Y662225D01*
X635906Y663109D01*
X636285Y663866D01*
X636853Y664497D01*
X637610Y664750D01*
X638273Y664624D01*
X638746Y664371D01*
X639220Y663866D01*
G01X652665Y664750D02*
Y659700D01*
G01Y666770D02*
X652476Y666896D01*
Y667149D01*
X652665Y667275D01*
X652855Y667149D01*
Y666896D01*
X652665Y666770D01*
G01X658631Y659700D02*
Y664750D01*
G01Y663487D02*
X659010Y664119D01*
X659578Y664624D01*
X660335Y664750D01*
X660998Y664624D01*
X661566Y664119D01*
X661850Y663235D01*
Y659700D01*
G01X672550D02*
Y664750D01*
G01Y663361D02*
X672834Y663993D01*
X673307Y664497D01*
X673970Y664750D01*
X674633Y664497D01*
X675106Y663993D01*
X675390Y663361D01*
Y659700D01*
G01Y663361D02*
X675675Y663993D01*
X676148Y664497D01*
X676811Y664750D01*
X677474Y664497D01*
X677947Y663993D01*
X678231Y663235D01*
Y659700D01*
G01X681545Y663109D02*
X684575D01*
X684291Y663993D01*
X683818Y664497D01*
X683155Y664750D01*
X682492Y664624D01*
X681924Y664245D01*
X681545Y663361D01*
X681356Y662604D01*
Y661846D01*
X681545Y661089D01*
X682019Y660331D01*
X682587Y659826D01*
X683250Y659700D01*
X683912Y659952D01*
X684575Y660710D01*
G01X692055Y664119D02*
X691393Y664624D01*
X690825Y664750D01*
X690067Y664497D01*
X689499Y663993D01*
X689120Y663109D01*
X689025Y662225D01*
X689120Y661341D01*
X689499Y660584D01*
X690067Y659952D01*
X690825Y659700D01*
X691487Y659952D01*
X692055Y660457D01*
G01X696506Y659700D02*
Y667275D01*
G01Y663614D02*
X696979Y664245D01*
X697453Y664624D01*
X698210Y664750D01*
X698778Y664624D01*
X699441Y664119D01*
X699725Y663361D01*
Y659700D01*
G01X707395D02*
Y664750D01*
G01Y663866D02*
X707016Y664371D01*
X706448Y664624D01*
X705785Y664750D01*
X705122Y664497D01*
X704554Y663993D01*
X704175Y663235D01*
X703986Y662225D01*
X704175Y661215D01*
X704554Y660457D01*
X705122Y659952D01*
X705785Y659700D01*
X706448Y659826D01*
X707016Y660205D01*
X707395Y660710D01*
G01X711656Y659700D02*
Y664750D01*
G01Y663487D02*
X712035Y664119D01*
X712603Y664624D01*
X713360Y664750D01*
X714023Y664624D01*
X714591Y664119D01*
X714875Y663235D01*
Y659700D01*
G01X720840Y664750D02*
Y659700D01*
G01Y666770D02*
X720651Y666896D01*
Y667149D01*
X720840Y667275D01*
X721030Y667149D01*
Y666896D01*
X720840Y666770D01*
G01X729930Y664119D02*
X729268Y664624D01*
X728700Y664750D01*
X727942Y664497D01*
X727374Y663993D01*
X726995Y663109D01*
X726900Y662225D01*
X726995Y661341D01*
X727374Y660584D01*
X727942Y659952D01*
X728700Y659700D01*
X729362Y659952D01*
X729930Y660457D01*
G01X737695Y659700D02*
Y664750D01*
G01Y663866D02*
X737316Y664371D01*
X736748Y664624D01*
X736085Y664750D01*
X735422Y664497D01*
X734854Y663993D01*
X734475Y663235D01*
X734286Y662225D01*
X734475Y661215D01*
X734854Y660457D01*
X735422Y659952D01*
X736085Y659700D01*
X736748Y659826D01*
X737316Y660205D01*
X737695Y660710D01*
G01X743565Y659700D02*
Y667275D01*
G01X760420D02*
Y659700D01*
G01Y660836D02*
X760041Y660205D01*
X759473Y659826D01*
X758810Y659700D01*
X758053Y659952D01*
X757485Y660584D01*
X757106Y661341D01*
X757011Y662225D01*
X757106Y663109D01*
X757485Y663866D01*
X758053Y664497D01*
X758810Y664750D01*
X759473Y664624D01*
X759946Y664371D01*
X760420Y663866D01*
G01X764965Y659700D02*
Y664750D01*
G01Y663740D02*
X765438Y664245D01*
X765912Y664624D01*
X766575Y664750D01*
X767048Y664624D01*
X767616Y664245D01*
G01X775570Y659700D02*
Y664750D01*
G01Y663866D02*
X775191Y664371D01*
X774623Y664624D01*
X773960Y664750D01*
X773297Y664497D01*
X772729Y663993D01*
X772350Y663235D01*
X772161Y662225D01*
X772350Y661215D01*
X772729Y660457D01*
X773297Y659952D01*
X773960Y659700D01*
X774623Y659826D01*
X775191Y660205D01*
X775570Y660710D01*
G01X779073Y664750D02*
X780210Y659700D01*
X781440Y664750D01*
X782671Y659700D01*
X783808Y664750D01*
G01X789015D02*
Y659700D01*
G01Y666770D02*
X788826Y666896D01*
Y667149D01*
X789015Y667275D01*
X789205Y667149D01*
Y666896D01*
X789015Y666770D01*
G01X794981Y659700D02*
Y664750D01*
G01Y663487D02*
X795360Y664119D01*
X795928Y664624D01*
X796685Y664750D01*
X797348Y664624D01*
X797916Y664119D01*
X798200Y663235D01*
Y659700D01*
G01X802840Y657806D02*
X803503Y657301D01*
X804260Y657175D01*
X804923Y657301D01*
X805491Y657932D01*
X805870Y658816D01*
Y664750D01*
G01Y663740D02*
X805491Y664245D01*
X804923Y664624D01*
X804260Y664750D01*
X803503Y664497D01*
X803029Y663993D01*
X802650Y663109D01*
X802461Y662225D01*
X802556Y661467D01*
X802935Y660584D01*
X803503Y659952D01*
X804260Y659700D01*
X804828Y659826D01*
X805491Y660331D01*
X805870Y660836D01*
G01X821020Y659700D02*
Y664750D01*
G01Y663866D02*
X820641Y664371D01*
X820073Y664624D01*
X819410Y664750D01*
X818747Y664497D01*
X818179Y663993D01*
X817800Y663235D01*
X817611Y662225D01*
X817800Y661215D01*
X818179Y660457D01*
X818747Y659952D01*
X819410Y659700D01*
X820073Y659826D01*
X820641Y660205D01*
X821020Y660710D01*
G01X825281Y659700D02*
Y664750D01*
G01Y663487D02*
X825660Y664119D01*
X826228Y664624D01*
X826985Y664750D01*
X827648Y664624D01*
X828216Y664119D01*
X828500Y663235D01*
Y659700D01*
G01X836170Y667275D02*
Y659700D01*
G01Y660836D02*
X835791Y660205D01*
X835223Y659826D01*
X834560Y659700D01*
X833803Y659952D01*
X833235Y660584D01*
X832856Y661341D01*
X832761Y662225D01*
X832856Y663109D01*
X833235Y663866D01*
X833803Y664497D01*
X834560Y664750D01*
X835223Y664624D01*
X835696Y664371D01*
X836170Y663866D01*
G01X848006Y659700D02*
Y667275D01*
G01Y663614D02*
X848479Y664245D01*
X848953Y664624D01*
X849710Y664750D01*
X850278Y664624D01*
X850941Y664119D01*
X851225Y663361D01*
Y659700D01*
G01X857190D02*
X856622Y659826D01*
X856054Y660331D01*
X855675Y661215D01*
X855486Y662225D01*
X855675Y663235D01*
X856054Y664119D01*
X856622Y664624D01*
X857190Y664750D01*
X857759Y664624D01*
X858327Y664119D01*
X858705Y663235D01*
X858800Y662225D01*
X858705Y661215D01*
X858327Y660331D01*
X857759Y659826D01*
X857190Y659700D01*
G01X864765D02*
Y667275D01*
G01X870920Y663109D02*
X873950D01*
X873666Y663993D01*
X873193Y664497D01*
X872530Y664750D01*
X871867Y664624D01*
X871299Y664245D01*
X870920Y663361D01*
X870731Y662604D01*
Y661846D01*
X870920Y661089D01*
X871394Y660331D01*
X871962Y659826D01*
X872625Y659700D01*
X873287Y659952D01*
X873950Y660710D01*
G01X885407Y659700D02*
Y667275D01*
X887301D01*
X888059Y666896D01*
X888627Y666391D01*
X889100Y665634D01*
X889479Y664750D01*
X889574Y663487D01*
X889479Y662225D01*
X889100Y661341D01*
X888627Y660584D01*
X888059Y660079D01*
X887301Y659700D01*
X885407D01*
G01X895065Y664750D02*
Y659700D01*
G01Y666770D02*
X894876Y666896D01*
Y667149D01*
X895065Y667275D01*
X895255Y667149D01*
Y666896D01*
X895065Y666770D01*
G01X904345Y659700D02*
Y664750D01*
G01Y663866D02*
X903966Y664371D01*
X903398Y664624D01*
X902735Y664750D01*
X902072Y664497D01*
X901504Y663993D01*
X901125Y663235D01*
X900936Y662225D01*
X901125Y661215D01*
X901504Y660457D01*
X902072Y659952D01*
X902735Y659700D01*
X903398Y659826D01*
X903966Y660205D01*
X904345Y660710D01*
G01X910215Y659448D02*
X910026Y659574D01*
Y659826D01*
X910215Y659952D01*
X910405Y659826D01*
Y659574D01*
X910215Y659448D01*
G01X925365Y659700D02*
Y667275D01*
X924229Y665760D01*
G01Y659700D02*
X926502D01*
G01X931141Y666013D02*
X931710Y666770D01*
X932372Y667149D01*
X933130Y667275D01*
X934077Y667023D01*
X934740Y666391D01*
X934929Y665634D01*
X934834Y664876D01*
X934455Y664245D01*
X932562Y662982D01*
X931710Y662099D01*
X931141Y660836D01*
X930952Y659700D01*
X934929D01*
G01X938716Y662856D02*
X939379Y663740D01*
X939947Y664245D01*
X940705Y664497D01*
X941368Y664245D01*
X941841Y663740D01*
X942220Y662982D01*
X942315Y662099D01*
X942220Y661341D01*
X941841Y660584D01*
X941273Y659952D01*
X940610Y659700D01*
X939853Y659952D01*
X939190Y660710D01*
X938811Y661846D01*
X938716Y663109D01*
X938906Y664750D01*
X939190Y665634D01*
X939663Y666517D01*
X940326Y667149D01*
X940989Y667275D01*
X941652Y667023D01*
X942125Y666391D01*
G01X945250Y659700D02*
Y664750D01*
G01Y663361D02*
X945534Y663993D01*
X946007Y664497D01*
X946670Y664750D01*
X947333Y664497D01*
X947806Y663993D01*
X948090Y663361D01*
Y659700D01*
G01Y663361D02*
X948375Y663993D01*
X948848Y664497D01*
X949511Y664750D01*
X950174Y664497D01*
X950647Y663993D01*
X950931Y663235D01*
Y659700D01*
G01X955665Y664750D02*
Y659700D01*
G01Y666770D02*
X955476Y666896D01*
Y667149D01*
X955665Y667275D01*
X955855Y667149D01*
Y666896D01*
X955665Y666770D01*
G01X963240Y659700D02*
Y667275D01*
G01X978390Y664750D02*
Y659700D01*
G01Y666770D02*
X978201Y666896D01*
Y667149D01*
X978390Y667275D01*
X978580Y667149D01*
Y666896D01*
X978390Y666770D01*
G01X984545Y660584D02*
X985019Y660079D01*
X985681Y659700D01*
X986250D01*
X986818Y659952D01*
X987196Y660331D01*
X987386Y660836D01*
X987291Y661594D01*
X986912Y661972D01*
X985208Y662730D01*
X984829Y663614D01*
X985019Y664245D01*
X985397Y664624D01*
X985965Y664750D01*
X986534Y664624D01*
X987102Y664245D01*
G01X998275Y659700D02*
Y664750D01*
G01Y663361D02*
X998559Y663993D01*
X999032Y664497D01*
X999695Y664750D01*
X1000358Y664497D01*
X1000831Y663993D01*
X1001115Y663361D01*
Y659700D01*
G01Y663361D02*
X1001400Y663993D01*
X1001873Y664497D01*
X1002536Y664750D01*
X1003199Y664497D01*
X1003672Y663993D01*
X1003956Y663235D01*
Y659700D01*
G01X1010395D02*
Y664750D01*
G01Y663866D02*
X1010016Y664371D01*
X1009448Y664624D01*
X1008785Y664750D01*
X1008122Y664497D01*
X1007554Y663993D01*
X1007175Y663235D01*
X1006986Y662225D01*
X1007175Y661215D01*
X1007554Y660457D01*
X1008122Y659952D01*
X1008785Y659700D01*
X1009448Y659826D01*
X1010016Y660205D01*
X1010395Y660710D01*
G01X1014940Y659700D02*
Y664750D01*
G01Y663740D02*
X1015413Y664245D01*
X1015887Y664624D01*
X1016550Y664750D01*
X1017023Y664624D01*
X1017591Y664245D01*
G01X1022231Y659700D02*
Y667275D01*
G01X1025261Y664750D02*
X1022231Y661846D01*
G01X1023462Y662982D02*
X1025450Y659700D01*
G01X1029995Y663109D02*
X1033025D01*
X1032741Y663993D01*
X1032268Y664497D01*
X1031605Y664750D01*
X1030942Y664624D01*
X1030374Y664245D01*
X1029995Y663361D01*
X1029806Y662604D01*
Y661846D01*
X1029995Y661089D01*
X1030469Y660331D01*
X1031037Y659826D01*
X1031700Y659700D01*
X1032362Y659952D01*
X1033025Y660710D01*
G01X1040695Y667275D02*
Y659700D01*
G01Y660836D02*
X1040316Y660205D01*
X1039748Y659826D01*
X1039085Y659700D01*
X1038328Y659952D01*
X1037760Y660584D01*
X1037381Y661341D01*
X1037286Y662225D01*
X1037381Y663109D01*
X1037760Y663866D01*
X1038328Y664497D01*
X1039085Y664750D01*
X1039748Y664624D01*
X1040221Y664371D01*
X1040695Y663866D01*
G01X1054140Y664750D02*
Y659700D01*
G01Y666770D02*
X1053951Y666896D01*
Y667149D01*
X1054140Y667275D01*
X1054330Y667149D01*
Y666896D01*
X1054140Y666770D01*
G01X1060106Y659700D02*
Y664750D01*
G01Y663487D02*
X1060485Y664119D01*
X1061053Y664624D01*
X1061810Y664750D01*
X1062473Y664624D01*
X1063041Y664119D01*
X1063325Y663235D01*
Y659700D01*
G01X1077434Y663487D02*
X1079327D01*
Y661215D01*
X1078759Y660457D01*
X1078096Y659952D01*
X1077150Y659700D01*
X1076203Y659952D01*
X1075540Y660457D01*
X1074972Y661215D01*
X1074593Y662099D01*
X1074404Y663109D01*
Y663993D01*
X1074593Y664750D01*
X1074972Y665634D01*
X1075540Y666391D01*
X1076108Y666896D01*
X1076865Y667275D01*
X1077528D01*
X1078286Y667023D01*
X1078854Y666517D01*
G01X1083020Y663109D02*
X1086050D01*
X1085766Y663993D01*
X1085293Y664497D01*
X1084630Y664750D01*
X1083967Y664624D01*
X1083399Y664245D01*
X1083020Y663361D01*
X1082831Y662604D01*
Y661846D01*
X1083020Y661089D01*
X1083494Y660331D01*
X1084062Y659826D01*
X1084725Y659700D01*
X1085387Y659952D01*
X1086050Y660710D01*
G01X1090690Y659700D02*
Y664750D01*
G01Y663740D02*
X1091163Y664245D01*
X1091637Y664624D01*
X1092300Y664750D01*
X1092773Y664624D01*
X1093341Y664245D01*
G01X1097886Y659700D02*
Y667275D01*
G01Y663487D02*
X1098360Y664245D01*
X1098928Y664624D01*
X1099496Y664750D01*
X1100348Y664497D01*
X1100916Y663993D01*
X1101295Y663109D01*
Y662099D01*
X1101105Y661089D01*
X1100727Y660331D01*
X1100064Y659826D01*
X1099496Y659700D01*
X1098928Y659826D01*
X1098360Y660205D01*
X1097886Y660836D01*
G01X1105745Y663109D02*
X1108775D01*
X1108491Y663993D01*
X1108018Y664497D01*
X1107355Y664750D01*
X1106692Y664624D01*
X1106124Y664245D01*
X1105745Y663361D01*
X1105556Y662604D01*
Y661846D01*
X1105745Y661089D01*
X1106219Y660331D01*
X1106787Y659826D01*
X1107450Y659700D01*
X1108112Y659952D01*
X1108775Y660710D01*
G01X1113415Y659700D02*
Y664750D01*
G01Y663740D02*
X1113888Y664245D01*
X1114362Y664624D01*
X1115025Y664750D01*
X1115498Y664624D01*
X1116066Y664245D01*
G01X1129322Y659700D02*
Y666139D01*
X1129512Y666770D01*
X1129890Y667149D01*
X1130459Y667275D01*
X1131027Y667023D01*
X1131311Y666391D01*
G01X1130175Y664245D02*
X1128281D01*
G01X1137465Y664750D02*
Y659700D01*
G01Y666770D02*
X1137276Y666896D01*
Y667149D01*
X1137465Y667275D01*
X1137655Y667149D01*
Y666896D01*
X1137465Y666770D01*
G01X1145040Y659700D02*
Y667275D01*
G01X1151195Y663109D02*
X1154225D01*
X1153941Y663993D01*
X1153468Y664497D01*
X1152805Y664750D01*
X1152142Y664624D01*
X1151574Y664245D01*
X1151195Y663361D01*
X1151006Y662604D01*
Y661846D01*
X1151195Y661089D01*
X1151669Y660331D01*
X1152237Y659826D01*
X1152900Y659700D01*
X1153562Y659952D01*
X1154225Y660710D01*
G01X1160190Y659448D02*
X1160001Y659574D01*
Y659826D01*
X1160190Y659952D01*
X1160380Y659826D01*
Y659574D01*
X1160190Y659448D01*
G01X355457Y691375D02*
Y685946D01*
X355836Y684810D01*
X356594Y684052D01*
X357540Y683800D01*
X358487Y684052D01*
X359245Y684810D01*
X359624Y685946D01*
Y691375D01*
G01X363506Y683800D02*
Y688850D01*
G01Y687587D02*
X363885Y688219D01*
X364453Y688724D01*
X365210Y688850D01*
X365873Y688724D01*
X366441Y688219D01*
X366725Y687335D01*
Y683800D01*
G01X372690Y688850D02*
Y683800D01*
G01Y690870D02*
X372501Y690996D01*
Y691249D01*
X372690Y691375D01*
X372880Y691249D01*
Y690996D01*
X372690Y690870D01*
G01X380265Y691375D02*
Y683800D01*
G01X378940Y688850D02*
X381591D01*
G01X396930Y688219D02*
X396268Y688724D01*
X395700Y688850D01*
X394942Y688597D01*
X394374Y688093D01*
X393995Y687209D01*
X393900Y686325D01*
X393995Y685441D01*
X394374Y684684D01*
X394942Y684052D01*
X395700Y683800D01*
X396362Y684052D01*
X396930Y684557D01*
G01X402990Y683800D02*
X402422Y683926D01*
X401854Y684431D01*
X401475Y685315D01*
X401286Y686325D01*
X401475Y687335D01*
X401854Y688219D01*
X402422Y688724D01*
X402990Y688850D01*
X403559Y688724D01*
X404127Y688219D01*
X404505Y687335D01*
X404600Y686325D01*
X404505Y685315D01*
X404127Y684431D01*
X403559Y683926D01*
X402990Y683800D01*
G01X408956D02*
Y688850D01*
G01Y687587D02*
X409335Y688219D01*
X409903Y688724D01*
X410660Y688850D01*
X411323Y688724D01*
X411891Y688219D01*
X412175Y687335D01*
Y683800D01*
G01X416436Y688850D02*
X418140Y683800D01*
X419845Y688850D01*
G01X424295Y687209D02*
X427325D01*
X427041Y688093D01*
X426568Y688597D01*
X425905Y688850D01*
X425242Y688724D01*
X424674Y688345D01*
X424295Y687461D01*
X424106Y686704D01*
Y685946D01*
X424295Y685189D01*
X424769Y684431D01*
X425337Y683926D01*
X426000Y683800D01*
X426662Y684052D01*
X427325Y684810D01*
G01X431965Y683800D02*
Y688850D01*
G01Y687840D02*
X432438Y688345D01*
X432912Y688724D01*
X433575Y688850D01*
X434048Y688724D01*
X434616Y688345D01*
G01X439445Y684684D02*
X439919Y684179D01*
X440581Y683800D01*
X441150D01*
X441718Y684052D01*
X442096Y684431D01*
X442286Y684936D01*
X442191Y685694D01*
X441812Y686072D01*
X440108Y686830D01*
X439729Y687714D01*
X439919Y688345D01*
X440297Y688724D01*
X440865Y688850D01*
X441434Y688724D01*
X442002Y688345D01*
G01X448440Y688850D02*
Y683800D01*
G01Y690870D02*
X448251Y690996D01*
Y691249D01*
X448440Y691375D01*
X448630Y691249D01*
Y690996D01*
X448440Y690870D01*
G01X456015Y683800D02*
X455447Y683926D01*
X454879Y684431D01*
X454500Y685315D01*
X454311Y686325D01*
X454500Y687335D01*
X454879Y688219D01*
X455447Y688724D01*
X456015Y688850D01*
X456584Y688724D01*
X457152Y688219D01*
X457530Y687335D01*
X457625Y686325D01*
X457530Y685315D01*
X457152Y684431D01*
X456584Y683926D01*
X456015Y683800D01*
G01X461981D02*
Y688850D01*
G01Y687587D02*
X462360Y688219D01*
X462928Y688724D01*
X463685Y688850D01*
X464348Y688724D01*
X464916Y688219D01*
X465200Y687335D01*
Y683800D01*
G01X477320Y687209D02*
X480350D01*
X480066Y688093D01*
X479593Y688597D01*
X478930Y688850D01*
X478267Y688724D01*
X477699Y688345D01*
X477320Y687461D01*
X477131Y686704D01*
Y685946D01*
X477320Y685189D01*
X477794Y684431D01*
X478362Y683926D01*
X479025Y683800D01*
X479687Y684052D01*
X480350Y684810D01*
G01X484990Y683800D02*
Y688850D01*
G01Y687840D02*
X485463Y688345D01*
X485937Y688724D01*
X486600Y688850D01*
X487073Y688724D01*
X487641Y688345D01*
G01X492565Y683800D02*
Y688850D01*
G01Y687840D02*
X493038Y688345D01*
X493512Y688724D01*
X494175Y688850D01*
X494648Y688724D01*
X495216Y688345D01*
G01X501465Y683800D02*
X500897Y683926D01*
X500329Y684431D01*
X499950Y685315D01*
X499761Y686325D01*
X499950Y687335D01*
X500329Y688219D01*
X500897Y688724D01*
X501465Y688850D01*
X502034Y688724D01*
X502602Y688219D01*
X502980Y687335D01*
X503075Y686325D01*
X502980Y685315D01*
X502602Y684431D01*
X502034Y683926D01*
X501465Y683800D01*
G01X507715D02*
Y688850D01*
G01Y687840D02*
X508188Y688345D01*
X508662Y688724D01*
X509325Y688850D01*
X509798Y688724D01*
X510366Y688345D01*
G01X522486Y683800D02*
Y691375D01*
G01Y687587D02*
X522960Y688345D01*
X523528Y688724D01*
X524096Y688850D01*
X524948Y688597D01*
X525516Y688093D01*
X525895Y687209D01*
Y686199D01*
X525705Y685189D01*
X525327Y684431D01*
X524664Y683926D01*
X524096Y683800D01*
X523528Y683926D01*
X522960Y684305D01*
X522486Y684936D01*
G01X530345Y687209D02*
X533375D01*
X533091Y688093D01*
X532618Y688597D01*
X531955Y688850D01*
X531292Y688724D01*
X530724Y688345D01*
X530345Y687461D01*
X530156Y686704D01*
Y685946D01*
X530345Y685189D01*
X530819Y684431D01*
X531387Y683926D01*
X532050Y683800D01*
X532712Y684052D01*
X533375Y684810D01*
G01X539340Y691375D02*
Y683800D01*
G01X538015Y688850D02*
X540666D01*
G01X544548D02*
X545685Y683800D01*
X546915Y688850D01*
X548146Y683800D01*
X549283Y688850D01*
G01X553070Y687209D02*
X556100D01*
X555816Y688093D01*
X555343Y688597D01*
X554680Y688850D01*
X554017Y688724D01*
X553449Y688345D01*
X553070Y687461D01*
X552881Y686704D01*
Y685946D01*
X553070Y685189D01*
X553544Y684431D01*
X554112Y683926D01*
X554775Y683800D01*
X555437Y684052D01*
X556100Y684810D01*
G01X560645Y687209D02*
X563675D01*
X563391Y688093D01*
X562918Y688597D01*
X562255Y688850D01*
X561592Y688724D01*
X561024Y688345D01*
X560645Y687461D01*
X560456Y686704D01*
Y685946D01*
X560645Y685189D01*
X561119Y684431D01*
X561687Y683926D01*
X562350Y683800D01*
X563012Y684052D01*
X563675Y684810D01*
G01X568031Y683800D02*
Y688850D01*
G01Y687587D02*
X568410Y688219D01*
X568978Y688724D01*
X569735Y688850D01*
X570398Y688724D01*
X570966Y688219D01*
X571250Y687335D01*
Y683800D01*
G01X581950D02*
Y688850D01*
G01Y687461D02*
X582234Y688093D01*
X582707Y688597D01*
X583370Y688850D01*
X584033Y688597D01*
X584506Y688093D01*
X584790Y687461D01*
Y683800D01*
G01Y687461D02*
X585075Y688093D01*
X585548Y688597D01*
X586211Y688850D01*
X586874Y688597D01*
X587347Y688093D01*
X587631Y687335D01*
Y683800D01*
G01X590945Y687209D02*
X593975D01*
X593691Y688093D01*
X593218Y688597D01*
X592555Y688850D01*
X591892Y688724D01*
X591324Y688345D01*
X590945Y687461D01*
X590756Y686704D01*
Y685946D01*
X590945Y685189D01*
X591419Y684431D01*
X591987Y683926D01*
X592650Y683800D01*
X593312Y684052D01*
X593975Y684810D01*
G01X599940Y691375D02*
Y683800D01*
G01X598615Y688850D02*
X601266D01*
G01X606190Y683800D02*
Y688850D01*
G01Y687840D02*
X606663Y688345D01*
X607137Y688724D01*
X607800Y688850D01*
X608273Y688724D01*
X608841Y688345D01*
G01X615090Y688850D02*
Y683800D01*
G01Y690870D02*
X614901Y690996D01*
Y691249D01*
X615090Y691375D01*
X615280Y691249D01*
Y690996D01*
X615090Y690870D01*
G01X624180Y688219D02*
X623518Y688724D01*
X622950Y688850D01*
X622192Y688597D01*
X621624Y688093D01*
X621245Y687209D01*
X621150Y686325D01*
X621245Y685441D01*
X621624Y684684D01*
X622192Y684052D01*
X622950Y683800D01*
X623612Y684052D01*
X624180Y684557D01*
G01X639520Y683800D02*
Y688850D01*
G01Y687966D02*
X639141Y688471D01*
X638573Y688724D01*
X637910Y688850D01*
X637247Y688597D01*
X636679Y688093D01*
X636300Y687335D01*
X636111Y686325D01*
X636300Y685315D01*
X636679Y684557D01*
X637247Y684052D01*
X637910Y683800D01*
X638573Y683926D01*
X639141Y684305D01*
X639520Y684810D01*
G01X643781Y683800D02*
Y688850D01*
G01Y687587D02*
X644160Y688219D01*
X644728Y688724D01*
X645485Y688850D01*
X646148Y688724D01*
X646716Y688219D01*
X647000Y687335D01*
Y683800D01*
G01X654670Y691375D02*
Y683800D01*
G01Y684936D02*
X654291Y684305D01*
X653723Y683926D01*
X653060Y683800D01*
X652303Y684052D01*
X651735Y684684D01*
X651356Y685441D01*
X651261Y686325D01*
X651356Y687209D01*
X651735Y687966D01*
X652303Y688597D01*
X653060Y688850D01*
X653723Y688724D01*
X654196Y688471D01*
X654670Y687966D01*
G01X670009Y683800D02*
X666222D01*
Y691375D01*
X670009D01*
G01X668494Y687714D02*
X666222D01*
G01X674081Y683800D02*
Y688850D01*
G01Y687587D02*
X674460Y688219D01*
X675028Y688724D01*
X675785Y688850D01*
X676448Y688724D01*
X677016Y688219D01*
X677300Y687335D01*
Y683800D01*
G01X681940Y681906D02*
X682603Y681401D01*
X683360Y681275D01*
X684023Y681401D01*
X684591Y682032D01*
X684970Y682916D01*
Y688850D01*
G01Y687840D02*
X684591Y688345D01*
X684023Y688724D01*
X683360Y688850D01*
X682603Y688597D01*
X682129Y688093D01*
X681750Y687209D01*
X681561Y686325D01*
X681656Y685567D01*
X682035Y684684D01*
X682603Y684052D01*
X683360Y683800D01*
X683928Y683926D01*
X684591Y684431D01*
X684970Y684936D01*
G01X690840Y683800D02*
Y691375D01*
G01X698415Y688850D02*
Y683800D01*
G01Y690870D02*
X698226Y690996D01*
Y691249D01*
X698415Y691375D01*
X698605Y691249D01*
Y690996D01*
X698415Y690870D01*
G01X704570Y684684D02*
X705044Y684179D01*
X705706Y683800D01*
X706275D01*
X706843Y684052D01*
X707221Y684431D01*
X707411Y684936D01*
X707316Y685694D01*
X706937Y686072D01*
X705233Y686830D01*
X704854Y687714D01*
X705044Y688345D01*
X705422Y688724D01*
X705990Y688850D01*
X706559Y688724D01*
X707127Y688345D01*
G01X711956Y683800D02*
Y691375D01*
G01Y687714D02*
X712429Y688345D01*
X712903Y688724D01*
X713660Y688850D01*
X714228Y688724D01*
X714891Y688219D01*
X715175Y687461D01*
Y683800D01*
G01X727295Y684684D02*
X727769Y684179D01*
X728431Y683800D01*
X729000D01*
X729568Y684052D01*
X729946Y684431D01*
X730136Y684936D01*
X730041Y685694D01*
X729662Y686072D01*
X727958Y686830D01*
X727579Y687714D01*
X727769Y688345D01*
X728147Y688724D01*
X728715Y688850D01*
X729284Y688724D01*
X729852Y688345D01*
G01X734302Y681528D02*
X734870Y681275D01*
X735628Y681528D01*
X736101Y682032D01*
X736480Y682664D01*
X737048Y684684D01*
X738279Y688850D01*
G01X735249D02*
X737048Y684684D01*
G01X742445D02*
X742919Y684179D01*
X743581Y683800D01*
X744150D01*
X744718Y684052D01*
X745096Y684431D01*
X745286Y684936D01*
X745191Y685694D01*
X744812Y686072D01*
X743108Y686830D01*
X742729Y687714D01*
X742919Y688345D01*
X743297Y688724D01*
X743865Y688850D01*
X744434Y688724D01*
X745002Y688345D01*
G01X751440Y691375D02*
Y683800D01*
G01X750115Y688850D02*
X752766D01*
G01X757595Y687209D02*
X760625D01*
X760341Y688093D01*
X759868Y688597D01*
X759205Y688850D01*
X758542Y688724D01*
X757974Y688345D01*
X757595Y687461D01*
X757406Y686704D01*
Y685946D01*
X757595Y685189D01*
X758069Y684431D01*
X758637Y683926D01*
X759300Y683800D01*
X759962Y684052D01*
X760625Y684810D01*
G01X763750Y683800D02*
Y688850D01*
G01Y687461D02*
X764034Y688093D01*
X764507Y688597D01*
X765170Y688850D01*
X765833Y688597D01*
X766306Y688093D01*
X766590Y687461D01*
Y683800D01*
G01Y687461D02*
X766875Y688093D01*
X767348Y688597D01*
X768011Y688850D01*
X768674Y688597D01*
X769147Y688093D01*
X769431Y687335D01*
Y683800D01*
G01X781740Y688850D02*
Y683800D01*
G01Y690870D02*
X781551Y690996D01*
Y691249D01*
X781740Y691375D01*
X781930Y691249D01*
Y690996D01*
X781740Y690870D01*
G01X787895Y684684D02*
X788369Y684179D01*
X789031Y683800D01*
X789600D01*
X790168Y684052D01*
X790546Y684431D01*
X790736Y684936D01*
X790641Y685694D01*
X790262Y686072D01*
X788558Y686830D01*
X788179Y687714D01*
X788369Y688345D01*
X788747Y688724D01*
X789315Y688850D01*
X789884Y688724D01*
X790452Y688345D01*
G01X804465Y683800D02*
Y691375D01*
G01X810620Y687209D02*
X813650D01*
X813366Y688093D01*
X812893Y688597D01*
X812230Y688850D01*
X811567Y688724D01*
X810999Y688345D01*
X810620Y687461D01*
X810431Y686704D01*
Y685946D01*
X810620Y685189D01*
X811094Y684431D01*
X811662Y683926D01*
X812325Y683800D01*
X812987Y684052D01*
X813650Y684810D01*
G01X818195Y684684D02*
X818669Y684179D01*
X819331Y683800D01*
X819900D01*
X820468Y684052D01*
X820846Y684431D01*
X821036Y684936D01*
X820941Y685694D01*
X820562Y686072D01*
X818858Y686830D01*
X818479Y687714D01*
X818669Y688345D01*
X819047Y688724D01*
X819615Y688850D01*
X820184Y688724D01*
X820752Y688345D01*
G01X825770Y684684D02*
X826244Y684179D01*
X826906Y683800D01*
X827475D01*
X828043Y684052D01*
X828421Y684431D01*
X828611Y684936D01*
X828516Y685694D01*
X828137Y686072D01*
X826433Y686830D01*
X826054Y687714D01*
X826244Y688345D01*
X826622Y688724D01*
X827190Y688850D01*
X827759Y688724D01*
X828327Y688345D01*
G01X842340Y691375D02*
Y683800D01*
G01X841015Y688850D02*
X843666D01*
G01X848306Y683800D02*
Y691375D01*
G01Y687714D02*
X848779Y688345D01*
X849253Y688724D01*
X850010Y688850D01*
X850578Y688724D01*
X851241Y688219D01*
X851525Y687461D01*
Y683800D01*
G01X859195D02*
Y688850D01*
G01Y687966D02*
X858816Y688471D01*
X858248Y688724D01*
X857585Y688850D01*
X856922Y688597D01*
X856354Y688093D01*
X855975Y687335D01*
X855786Y686325D01*
X855975Y685315D01*
X856354Y684557D01*
X856922Y684052D01*
X857585Y683800D01*
X858248Y683926D01*
X858816Y684305D01*
X859195Y684810D01*
G01X863456Y683800D02*
Y688850D01*
G01Y687587D02*
X863835Y688219D01*
X864403Y688724D01*
X865160Y688850D01*
X865823Y688724D01*
X866391Y688219D01*
X866675Y687335D01*
Y683800D01*
G01X880215D02*
Y691375D01*
X879079Y689860D01*
G01Y683800D02*
X881352D01*
G01X892525D02*
Y688850D01*
G01Y687461D02*
X892809Y688093D01*
X893282Y688597D01*
X893945Y688850D01*
X894608Y688597D01*
X895081Y688093D01*
X895365Y687461D01*
Y683800D01*
G01Y687461D02*
X895650Y688093D01*
X896123Y688597D01*
X896786Y688850D01*
X897449Y688597D01*
X897922Y688093D01*
X898206Y687335D01*
Y683800D01*
G01X902940Y688850D02*
Y683800D01*
G01Y690870D02*
X902751Y690996D01*
Y691249D01*
X902940Y691375D01*
X903130Y691249D01*
Y690996D01*
X902940Y690870D01*
G01X910515Y683800D02*
Y691375D01*
G01X917901Y682411D02*
X918280Y684052D01*
G01X931536Y681275D02*
Y688850D01*
G01Y687714D02*
X932010Y688345D01*
X932483Y688724D01*
X933240Y688850D01*
X933903Y688724D01*
X934566Y688093D01*
X934850Y687209D01*
X934945Y686325D01*
X934850Y685441D01*
X934566Y684557D01*
X933998Y684052D01*
X933240Y683800D01*
X932578Y683926D01*
X931915Y684305D01*
X931536Y684810D01*
G01X940815Y683800D02*
Y691375D01*
G01X946970Y687209D02*
X950000D01*
X949716Y688093D01*
X949243Y688597D01*
X948580Y688850D01*
X947917Y688724D01*
X947349Y688345D01*
X946970Y687461D01*
X946781Y686704D01*
Y685946D01*
X946970Y685189D01*
X947444Y684431D01*
X948012Y683926D01*
X948675Y683800D01*
X949337Y684052D01*
X950000Y684810D01*
G01X957670Y683800D02*
Y688850D01*
G01Y687966D02*
X957291Y688471D01*
X956723Y688724D01*
X956060Y688850D01*
X955397Y688597D01*
X954829Y688093D01*
X954450Y687335D01*
X954261Y686325D01*
X954450Y685315D01*
X954829Y684557D01*
X955397Y684052D01*
X956060Y683800D01*
X956723Y683926D01*
X957291Y684305D01*
X957670Y684810D01*
G01X962120Y684684D02*
X962594Y684179D01*
X963256Y683800D01*
X963825D01*
X964393Y684052D01*
X964771Y684431D01*
X964961Y684936D01*
X964866Y685694D01*
X964487Y686072D01*
X962783Y686830D01*
X962404Y687714D01*
X962594Y688345D01*
X962972Y688724D01*
X963540Y688850D01*
X964109Y688724D01*
X964677Y688345D01*
G01X969695Y687209D02*
X972725D01*
X972441Y688093D01*
X971968Y688597D01*
X971305Y688850D01*
X970642Y688724D01*
X970074Y688345D01*
X969695Y687461D01*
X969506Y686704D01*
Y685946D01*
X969695Y685189D01*
X970169Y684431D01*
X970737Y683926D01*
X971400Y683800D01*
X972062Y684052D01*
X972725Y684810D01*
G01X985697Y683800D02*
Y690239D01*
X985887Y690870D01*
X986265Y691249D01*
X986834Y691375D01*
X987402Y691123D01*
X987686Y690491D01*
G01X986550Y688345D02*
X984656D01*
G01X993840Y683800D02*
X993272Y683926D01*
X992704Y684431D01*
X992325Y685315D01*
X992136Y686325D01*
X992325Y687335D01*
X992704Y688219D01*
X993272Y688724D01*
X993840Y688850D01*
X994409Y688724D01*
X994977Y688219D01*
X995355Y687335D01*
X995450Y686325D01*
X995355Y685315D01*
X994977Y684431D01*
X994409Y683926D01*
X993840Y683800D01*
G01X1001415D02*
Y691375D01*
G01X1008990Y683800D02*
Y691375D01*
G01X1016565Y683800D02*
X1015997Y683926D01*
X1015429Y684431D01*
X1015050Y685315D01*
X1014861Y686325D01*
X1015050Y687335D01*
X1015429Y688219D01*
X1015997Y688724D01*
X1016565Y688850D01*
X1017134Y688724D01*
X1017702Y688219D01*
X1018080Y687335D01*
X1018175Y686325D01*
X1018080Y685315D01*
X1017702Y684431D01*
X1017134Y683926D01*
X1016565Y683800D01*
G01X1021773Y688850D02*
X1022910Y683800D01*
X1024140Y688850D01*
X1025371Y683800D01*
X1026508Y688850D01*
G01X1036450Y683800D02*
Y688850D01*
G01Y687461D02*
X1036734Y688093D01*
X1037207Y688597D01*
X1037870Y688850D01*
X1038533Y688597D01*
X1039006Y688093D01*
X1039290Y687461D01*
Y683800D01*
G01Y687461D02*
X1039575Y688093D01*
X1040048Y688597D01*
X1040711Y688850D01*
X1041374Y688597D01*
X1041847Y688093D01*
X1042131Y687335D01*
Y683800D01*
G01X1045445Y687209D02*
X1048475D01*
X1048191Y688093D01*
X1047718Y688597D01*
X1047055Y688850D01*
X1046392Y688724D01*
X1045824Y688345D01*
X1045445Y687461D01*
X1045256Y686704D01*
Y685946D01*
X1045445Y685189D01*
X1045919Y684431D01*
X1046487Y683926D01*
X1047150Y683800D01*
X1047812Y684052D01*
X1048475Y684810D01*
G01X1055955Y688219D02*
X1055293Y688724D01*
X1054725Y688850D01*
X1053967Y688597D01*
X1053399Y688093D01*
X1053020Y687209D01*
X1052925Y686325D01*
X1053020Y685441D01*
X1053399Y684684D01*
X1053967Y684052D01*
X1054725Y683800D01*
X1055387Y684052D01*
X1055955Y684557D01*
G01X1060406Y683800D02*
Y691375D01*
G01Y687714D02*
X1060879Y688345D01*
X1061353Y688724D01*
X1062110Y688850D01*
X1062678Y688724D01*
X1063341Y688219D01*
X1063625Y687461D01*
Y683800D01*
G01X1071295D02*
Y688850D01*
G01Y687966D02*
X1070916Y688471D01*
X1070348Y688724D01*
X1069685Y688850D01*
X1069022Y688597D01*
X1068454Y688093D01*
X1068075Y687335D01*
X1067886Y686325D01*
X1068075Y685315D01*
X1068454Y684557D01*
X1069022Y684052D01*
X1069685Y683800D01*
X1070348Y683926D01*
X1070916Y684305D01*
X1071295Y684810D01*
G01X1075556Y683800D02*
Y688850D01*
G01Y687587D02*
X1075935Y688219D01*
X1076503Y688724D01*
X1077260Y688850D01*
X1077923Y688724D01*
X1078491Y688219D01*
X1078775Y687335D01*
Y683800D01*
G01X1084740Y688850D02*
Y683800D01*
G01Y690870D02*
X1084551Y690996D01*
Y691249D01*
X1084740Y691375D01*
X1084930Y691249D01*
Y690996D01*
X1084740Y690870D01*
G01X1093830Y688219D02*
X1093168Y688724D01*
X1092600Y688850D01*
X1091842Y688597D01*
X1091274Y688093D01*
X1090895Y687209D01*
X1090800Y686325D01*
X1090895Y685441D01*
X1091274Y684684D01*
X1091842Y684052D01*
X1092600Y683800D01*
X1093262Y684052D01*
X1093830Y684557D01*
G01X1101595Y683800D02*
Y688850D01*
G01Y687966D02*
X1101216Y688471D01*
X1100648Y688724D01*
X1099985Y688850D01*
X1099322Y688597D01*
X1098754Y688093D01*
X1098375Y687335D01*
X1098186Y686325D01*
X1098375Y685315D01*
X1098754Y684557D01*
X1099322Y684052D01*
X1099985Y683800D01*
X1100648Y683926D01*
X1101216Y684305D01*
X1101595Y684810D01*
G01X1107465Y683800D02*
Y691375D01*
G01X1124320D02*
Y683800D01*
G01Y684936D02*
X1123941Y684305D01*
X1123373Y683926D01*
X1122710Y683800D01*
X1121953Y684052D01*
X1121385Y684684D01*
X1121006Y685441D01*
X1120911Y686325D01*
X1121006Y687209D01*
X1121385Y687966D01*
X1121953Y688597D01*
X1122710Y688850D01*
X1123373Y688724D01*
X1123846Y688471D01*
X1124320Y687966D01*
G01X1128865Y683800D02*
Y688850D01*
G01Y687840D02*
X1129338Y688345D01*
X1129812Y688724D01*
X1130475Y688850D01*
X1130948Y688724D01*
X1131516Y688345D01*
G01X1139470Y683800D02*
Y688850D01*
G01Y687966D02*
X1139091Y688471D01*
X1138523Y688724D01*
X1137860Y688850D01*
X1137197Y688597D01*
X1136629Y688093D01*
X1136250Y687335D01*
X1136061Y686325D01*
X1136250Y685315D01*
X1136629Y684557D01*
X1137197Y684052D01*
X1137860Y683800D01*
X1138523Y683926D01*
X1139091Y684305D01*
X1139470Y684810D01*
G01X1142973Y688850D02*
X1144110Y683800D01*
X1145340Y688850D01*
X1146571Y683800D01*
X1147708Y688850D01*
G01X1152915D02*
Y683800D01*
G01Y690870D02*
X1152726Y690996D01*
Y691249D01*
X1152915Y691375D01*
X1153105Y691249D01*
Y690996D01*
X1152915Y690870D01*
G01X1158881Y683800D02*
Y688850D01*
G01Y687587D02*
X1159260Y688219D01*
X1159828Y688724D01*
X1160585Y688850D01*
X1161248Y688724D01*
X1161816Y688219D01*
X1162100Y687335D01*
Y683800D01*
G01X1166740Y681906D02*
X1167403Y681401D01*
X1168160Y681275D01*
X1168823Y681401D01*
X1169391Y682032D01*
X1169770Y682916D01*
Y688850D01*
G01Y687840D02*
X1169391Y688345D01*
X1168823Y688724D01*
X1168160Y688850D01*
X1167403Y688597D01*
X1166929Y688093D01*
X1166550Y687209D01*
X1166361Y686325D01*
X1166456Y685567D01*
X1166835Y684684D01*
X1167403Y684052D01*
X1168160Y683800D01*
X1168728Y683926D01*
X1169391Y684431D01*
X1169770Y684936D01*
G01X1174978Y681528D02*
X1176303Y683295D01*
Y685062D01*
X1174978D01*
Y683295D01*
X1176303D01*
G01Y686325D02*
Y688093D01*
X1174978D01*
Y686325D01*
X1176303D01*
G01X355604Y679075D02*
X357877D01*
G01X356740D02*
Y671500D01*
G01X355604D02*
X357877D01*
G01X363747D02*
Y677939D01*
X363937Y678570D01*
X364315Y678949D01*
X364884Y679075D01*
X365452Y678823D01*
X365736Y678191D01*
G01X364600Y676045D02*
X362706D01*
G01X379465Y676550D02*
Y671500D01*
G01Y678570D02*
X379276Y678696D01*
Y678949D01*
X379465Y679075D01*
X379655Y678949D01*
Y678696D01*
X379465Y678570D01*
G01X385620Y672384D02*
X386094Y671879D01*
X386756Y671500D01*
X387325D01*
X387893Y671752D01*
X388271Y672131D01*
X388461Y672636D01*
X388366Y673394D01*
X387987Y673772D01*
X386283Y674530D01*
X385904Y675414D01*
X386094Y676045D01*
X386472Y676424D01*
X387040Y676550D01*
X387609Y676424D01*
X388177Y676045D01*
G01X400865Y669606D02*
X401528Y669101D01*
X402285Y668975D01*
X402948Y669101D01*
X403516Y669732D01*
X403895Y670616D01*
Y676550D01*
G01Y675540D02*
X403516Y676045D01*
X402948Y676424D01*
X402285Y676550D01*
X401528Y676297D01*
X401054Y675793D01*
X400675Y674909D01*
X400486Y674025D01*
X400581Y673267D01*
X400960Y672384D01*
X401528Y671752D01*
X402285Y671500D01*
X402853Y671626D01*
X403516Y672131D01*
X403895Y672636D01*
G01X408440Y671500D02*
Y676550D01*
G01Y675540D02*
X408913Y676045D01*
X409387Y676424D01*
X410050Y676550D01*
X410523Y676424D01*
X411091Y676045D01*
G01X415920Y674909D02*
X418950D01*
X418666Y675793D01*
X418193Y676297D01*
X417530Y676550D01*
X416867Y676424D01*
X416299Y676045D01*
X415920Y675161D01*
X415731Y674404D01*
Y673646D01*
X415920Y672889D01*
X416394Y672131D01*
X416962Y671626D01*
X417625Y671500D01*
X418287Y671752D01*
X418950Y672510D01*
G01X426620Y671500D02*
Y676550D01*
G01Y675666D02*
X426241Y676171D01*
X425673Y676424D01*
X425010Y676550D01*
X424347Y676297D01*
X423779Y675793D01*
X423400Y675035D01*
X423211Y674025D01*
X423400Y673015D01*
X423779Y672257D01*
X424347Y671752D01*
X425010Y671500D01*
X425673Y671626D01*
X426241Y672005D01*
X426620Y672510D01*
G01X432490Y679075D02*
Y671500D01*
G01X431165Y676550D02*
X433816D01*
G01X438645Y674909D02*
X441675D01*
X441391Y675793D01*
X440918Y676297D01*
X440255Y676550D01*
X439592Y676424D01*
X439024Y676045D01*
X438645Y675161D01*
X438456Y674404D01*
Y673646D01*
X438645Y672889D01*
X439119Y672131D01*
X439687Y671626D01*
X440350Y671500D01*
X441012Y671752D01*
X441675Y672510D01*
G01X446315Y671500D02*
Y676550D01*
G01Y675540D02*
X446788Y676045D01*
X447262Y676424D01*
X447925Y676550D01*
X448398Y676424D01*
X448966Y676045D01*
G01X462790Y679075D02*
Y671500D01*
G01X461465Y676550D02*
X464116D01*
G01X468756Y671500D02*
Y679075D01*
G01Y675414D02*
X469229Y676045D01*
X469703Y676424D01*
X470460Y676550D01*
X471028Y676424D01*
X471691Y675919D01*
X471975Y675161D01*
Y671500D01*
G01X479645D02*
Y676550D01*
G01Y675666D02*
X479266Y676171D01*
X478698Y676424D01*
X478035Y676550D01*
X477372Y676297D01*
X476804Y675793D01*
X476425Y675035D01*
X476236Y674025D01*
X476425Y673015D01*
X476804Y672257D01*
X477372Y671752D01*
X478035Y671500D01*
X478698Y671626D01*
X479266Y672005D01*
X479645Y672510D01*
G01X483906Y671500D02*
Y676550D01*
G01Y675287D02*
X484285Y675919D01*
X484853Y676424D01*
X485610Y676550D01*
X486273Y676424D01*
X486841Y675919D01*
X487125Y675035D01*
Y671500D01*
G01X500665D02*
Y679075D01*
X499529Y677560D01*
G01Y671500D02*
X501802D01*
G01X512975D02*
Y676550D01*
G01Y675161D02*
X513259Y675793D01*
X513732Y676297D01*
X514395Y676550D01*
X515058Y676297D01*
X515531Y675793D01*
X515815Y675161D01*
Y671500D01*
G01Y675161D02*
X516100Y675793D01*
X516573Y676297D01*
X517236Y676550D01*
X517899Y676297D01*
X518372Y675793D01*
X518656Y675035D01*
Y671500D01*
G01X523390Y676550D02*
Y671500D01*
G01Y678570D02*
X523201Y678696D01*
Y678949D01*
X523390Y679075D01*
X523580Y678949D01*
Y678696D01*
X523390Y678570D01*
G01X529545Y672384D02*
X530019Y671879D01*
X530681Y671500D01*
X531250D01*
X531818Y671752D01*
X532196Y672131D01*
X532386Y672636D01*
X532291Y673394D01*
X531912Y673772D01*
X530208Y674530D01*
X529829Y675414D01*
X530019Y676045D01*
X530397Y676424D01*
X530965Y676550D01*
X531534Y676424D01*
X532102Y676045D01*
G01X538351Y670111D02*
X538730Y671752D01*
G01X551986Y668975D02*
Y676550D01*
G01Y675414D02*
X552460Y676045D01*
X552933Y676424D01*
X553690Y676550D01*
X554353Y676424D01*
X555016Y675793D01*
X555300Y674909D01*
X555395Y674025D01*
X555300Y673141D01*
X555016Y672257D01*
X554448Y671752D01*
X553690Y671500D01*
X553028Y671626D01*
X552365Y672005D01*
X551986Y672510D01*
G01X561265Y671500D02*
Y679075D01*
G01X567420Y674909D02*
X570450D01*
X570166Y675793D01*
X569693Y676297D01*
X569030Y676550D01*
X568367Y676424D01*
X567799Y676045D01*
X567420Y675161D01*
X567231Y674404D01*
Y673646D01*
X567420Y672889D01*
X567894Y672131D01*
X568462Y671626D01*
X569125Y671500D01*
X569787Y671752D01*
X570450Y672510D01*
G01X578120Y671500D02*
Y676550D01*
G01Y675666D02*
X577741Y676171D01*
X577173Y676424D01*
X576510Y676550D01*
X575847Y676297D01*
X575279Y675793D01*
X574900Y675035D01*
X574711Y674025D01*
X574900Y673015D01*
X575279Y672257D01*
X575847Y671752D01*
X576510Y671500D01*
X577173Y671626D01*
X577741Y672005D01*
X578120Y672510D01*
G01X582570Y672384D02*
X583044Y671879D01*
X583706Y671500D01*
X584275D01*
X584843Y671752D01*
X585221Y672131D01*
X585411Y672636D01*
X585316Y673394D01*
X584937Y673772D01*
X583233Y674530D01*
X582854Y675414D01*
X583044Y676045D01*
X583422Y676424D01*
X583990Y676550D01*
X584559Y676424D01*
X585127Y676045D01*
G01X590145Y674909D02*
X593175D01*
X592891Y675793D01*
X592418Y676297D01*
X591755Y676550D01*
X591092Y676424D01*
X590524Y676045D01*
X590145Y675161D01*
X589956Y674404D01*
Y673646D01*
X590145Y672889D01*
X590619Y672131D01*
X591187Y671626D01*
X591850Y671500D01*
X592512Y671752D01*
X593175Y672510D01*
G01X606715Y676550D02*
Y671500D01*
G01Y678570D02*
X606526Y678696D01*
Y678949D01*
X606715Y679075D01*
X606905Y678949D01*
Y678696D01*
X606715Y678570D01*
G01X612870Y672384D02*
X613344Y671879D01*
X614006Y671500D01*
X614575D01*
X615143Y671752D01*
X615521Y672131D01*
X615711Y672636D01*
X615616Y673394D01*
X615237Y673772D01*
X613533Y674530D01*
X613154Y675414D01*
X613344Y676045D01*
X613722Y676424D01*
X614290Y676550D01*
X614859Y676424D01*
X615427Y676045D01*
G01X620445Y672384D02*
X620919Y671879D01*
X621581Y671500D01*
X622150D01*
X622718Y671752D01*
X623096Y672131D01*
X623286Y672636D01*
X623191Y673394D01*
X622812Y673772D01*
X621108Y674530D01*
X620729Y675414D01*
X620919Y676045D01*
X621297Y676424D01*
X621865Y676550D01*
X622434Y676424D01*
X623002Y676045D01*
G01X627831Y676550D02*
Y673015D01*
X628210Y672131D01*
X628778Y671626D01*
X629440Y671500D01*
X630103Y671626D01*
X630671Y672131D01*
X631050Y673015D01*
G01Y671500D02*
Y676550D01*
G01X635595Y674909D02*
X638625D01*
X638341Y675793D01*
X637868Y676297D01*
X637205Y676550D01*
X636542Y676424D01*
X635974Y676045D01*
X635595Y675161D01*
X635406Y674404D01*
Y673646D01*
X635595Y672889D01*
X636069Y672131D01*
X636637Y671626D01*
X637300Y671500D01*
X637962Y671752D01*
X638625Y672510D01*
G01X650745Y674909D02*
X653775D01*
X653491Y675793D01*
X653018Y676297D01*
X652355Y676550D01*
X651692Y676424D01*
X651124Y676045D01*
X650745Y675161D01*
X650556Y674404D01*
Y673646D01*
X650745Y672889D01*
X651219Y672131D01*
X651787Y671626D01*
X652450Y671500D01*
X653112Y671752D01*
X653775Y672510D01*
G01X658131Y671500D02*
Y676550D01*
G01Y675287D02*
X658510Y675919D01*
X659078Y676424D01*
X659835Y676550D01*
X660498Y676424D01*
X661066Y675919D01*
X661350Y675035D01*
Y671500D01*
G01X665990Y669606D02*
X666653Y669101D01*
X667410Y668975D01*
X668073Y669101D01*
X668641Y669732D01*
X669020Y670616D01*
Y676550D01*
G01Y675540D02*
X668641Y676045D01*
X668073Y676424D01*
X667410Y676550D01*
X666653Y676297D01*
X666179Y675793D01*
X665800Y674909D01*
X665611Y674025D01*
X665706Y673267D01*
X666085Y672384D01*
X666653Y671752D01*
X667410Y671500D01*
X667978Y671626D01*
X668641Y672131D01*
X669020Y672636D01*
G01X674890Y676550D02*
Y671500D01*
G01Y678570D02*
X674701Y678696D01*
Y678949D01*
X674890Y679075D01*
X675080Y678949D01*
Y678696D01*
X674890Y678570D01*
G01X680856Y671500D02*
Y676550D01*
G01Y675287D02*
X681235Y675919D01*
X681803Y676424D01*
X682560Y676550D01*
X683223Y676424D01*
X683791Y675919D01*
X684075Y675035D01*
Y671500D01*
G01X688620Y674909D02*
X691650D01*
X691366Y675793D01*
X690893Y676297D01*
X690230Y676550D01*
X689567Y676424D01*
X688999Y676045D01*
X688620Y675161D01*
X688431Y674404D01*
Y673646D01*
X688620Y672889D01*
X689094Y672131D01*
X689662Y671626D01*
X690325Y671500D01*
X690987Y671752D01*
X691650Y672510D01*
G01X696195Y674909D02*
X699225D01*
X698941Y675793D01*
X698468Y676297D01*
X697805Y676550D01*
X697142Y676424D01*
X696574Y676045D01*
X696195Y675161D01*
X696006Y674404D01*
Y673646D01*
X696195Y672889D01*
X696669Y672131D01*
X697237Y671626D01*
X697900Y671500D01*
X698562Y671752D01*
X699225Y672510D01*
G01X703865Y671500D02*
Y676550D01*
G01Y675540D02*
X704338Y676045D01*
X704812Y676424D01*
X705475Y676550D01*
X705948Y676424D01*
X706516Y676045D01*
G01X712765Y676550D02*
Y671500D01*
G01Y678570D02*
X712576Y678696D01*
Y678949D01*
X712765Y679075D01*
X712955Y678949D01*
Y678696D01*
X712765Y678570D01*
G01X718731Y671500D02*
Y676550D01*
G01Y675287D02*
X719110Y675919D01*
X719678Y676424D01*
X720435Y676550D01*
X721098Y676424D01*
X721666Y675919D01*
X721950Y675035D01*
Y671500D01*
G01X726590Y669606D02*
X727253Y669101D01*
X728010Y668975D01*
X728673Y669101D01*
X729241Y669732D01*
X729620Y670616D01*
Y676550D01*
G01Y675540D02*
X729241Y676045D01*
X728673Y676424D01*
X728010Y676550D01*
X727253Y676297D01*
X726779Y675793D01*
X726400Y674909D01*
X726211Y674025D01*
X726306Y673267D01*
X726685Y672384D01*
X727253Y671752D01*
X728010Y671500D01*
X728578Y671626D01*
X729241Y672131D01*
X729620Y672636D01*
G01X744770Y668975D02*
Y676550D01*
G01Y675414D02*
X744296Y676045D01*
X743728Y676424D01*
X743065Y676550D01*
X742497Y676424D01*
X741835Y675793D01*
X741456Y674909D01*
X741361Y674025D01*
X741456Y673141D01*
X741835Y672257D01*
X742497Y671626D01*
X743065Y671500D01*
X743728Y671626D01*
X744296Y672005D01*
X744770Y672636D01*
G01X749031Y676550D02*
Y673015D01*
X749410Y672131D01*
X749978Y671626D01*
X750640Y671500D01*
X751303Y671626D01*
X751871Y672131D01*
X752250Y673015D01*
G01Y671500D02*
Y676550D01*
G01X756795Y674909D02*
X759825D01*
X759541Y675793D01*
X759068Y676297D01*
X758405Y676550D01*
X757742Y676424D01*
X757174Y676045D01*
X756795Y675161D01*
X756606Y674404D01*
Y673646D01*
X756795Y672889D01*
X757269Y672131D01*
X757837Y671626D01*
X758500Y671500D01*
X759162Y671752D01*
X759825Y672510D01*
G01X764465Y671500D02*
Y676550D01*
G01Y675540D02*
X764938Y676045D01*
X765412Y676424D01*
X766075Y676550D01*
X766548Y676424D01*
X767116Y676045D01*
G01X771377Y669228D02*
X771945Y668975D01*
X772703Y669228D01*
X773176Y669732D01*
X773555Y670364D01*
X774123Y672384D01*
X775354Y676550D01*
G01X772324D02*
X774123Y672384D01*
G01X780940Y671248D02*
X780751Y671374D01*
Y671626D01*
X780940Y671752D01*
X781130Y671626D01*
Y671374D01*
X780940Y671248D01*
G01X355257Y703175D02*
Y697746D01*
X355636Y696610D01*
X356394Y695852D01*
X357340Y695600D01*
X358287Y695852D01*
X359045Y696610D01*
X359424Y697746D01*
Y703175D01*
G01X363306Y695600D02*
Y700650D01*
G01Y699387D02*
X363685Y700019D01*
X364253Y700524D01*
X365010Y700650D01*
X365673Y700524D01*
X366241Y700019D01*
X366525Y699135D01*
Y695600D01*
G01X372490Y700650D02*
Y695600D01*
G01Y702670D02*
X372301Y702796D01*
Y703049D01*
X372490Y703175D01*
X372680Y703049D01*
Y702796D01*
X372490Y702670D01*
G01X380065Y703175D02*
Y695600D01*
G01X378740Y700650D02*
X381391D01*
G01X396730Y700019D02*
X396068Y700524D01*
X395500Y700650D01*
X394742Y700397D01*
X394174Y699893D01*
X393795Y699009D01*
X393700Y698125D01*
X393795Y697241D01*
X394174Y696484D01*
X394742Y695852D01*
X395500Y695600D01*
X396162Y695852D01*
X396730Y696357D01*
G01X402790Y695600D02*
X402222Y695726D01*
X401654Y696231D01*
X401275Y697115D01*
X401086Y698125D01*
X401275Y699135D01*
X401654Y700019D01*
X402222Y700524D01*
X402790Y700650D01*
X403359Y700524D01*
X403927Y700019D01*
X404305Y699135D01*
X404400Y698125D01*
X404305Y697115D01*
X403927Y696231D01*
X403359Y695726D01*
X402790Y695600D01*
G01X408756D02*
Y700650D01*
G01Y699387D02*
X409135Y700019D01*
X409703Y700524D01*
X410460Y700650D01*
X411123Y700524D01*
X411691Y700019D01*
X411975Y699135D01*
Y695600D01*
G01X416236Y700650D02*
X417940Y695600D01*
X419645Y700650D01*
G01X424095Y699009D02*
X427125D01*
X426841Y699893D01*
X426368Y700397D01*
X425705Y700650D01*
X425042Y700524D01*
X424474Y700145D01*
X424095Y699261D01*
X423906Y698504D01*
Y697746D01*
X424095Y696989D01*
X424569Y696231D01*
X425137Y695726D01*
X425800Y695600D01*
X426462Y695852D01*
X427125Y696610D01*
G01X431765Y695600D02*
Y700650D01*
G01Y699640D02*
X432238Y700145D01*
X432712Y700524D01*
X433375Y700650D01*
X433848Y700524D01*
X434416Y700145D01*
G01X439245Y696484D02*
X439719Y695979D01*
X440381Y695600D01*
X440950D01*
X441518Y695852D01*
X441896Y696231D01*
X442086Y696736D01*
X441991Y697494D01*
X441612Y697872D01*
X439908Y698630D01*
X439529Y699514D01*
X439719Y700145D01*
X440097Y700524D01*
X440665Y700650D01*
X441234Y700524D01*
X441802Y700145D01*
G01X448240Y700650D02*
Y695600D01*
G01Y702670D02*
X448051Y702796D01*
Y703049D01*
X448240Y703175D01*
X448430Y703049D01*
Y702796D01*
X448240Y702670D01*
G01X455815Y695600D02*
X455247Y695726D01*
X454679Y696231D01*
X454300Y697115D01*
X454111Y698125D01*
X454300Y699135D01*
X454679Y700019D01*
X455247Y700524D01*
X455815Y700650D01*
X456384Y700524D01*
X456952Y700019D01*
X457330Y699135D01*
X457425Y698125D01*
X457330Y697115D01*
X456952Y696231D01*
X456384Y695726D01*
X455815Y695600D01*
G01X461781D02*
Y700650D01*
G01Y699387D02*
X462160Y700019D01*
X462728Y700524D01*
X463485Y700650D01*
X464148Y700524D01*
X464716Y700019D01*
X465000Y699135D01*
Y695600D01*
G01X478540Y700650D02*
Y695600D01*
G01Y702670D02*
X478351Y702796D01*
Y703049D01*
X478540Y703175D01*
X478730Y703049D01*
Y702796D01*
X478540Y702670D01*
G01X484695Y696484D02*
X485169Y695979D01*
X485831Y695600D01*
X486400D01*
X486968Y695852D01*
X487346Y696231D01*
X487536Y696736D01*
X487441Y697494D01*
X487062Y697872D01*
X485358Y698630D01*
X484979Y699514D01*
X485169Y700145D01*
X485547Y700524D01*
X486115Y700650D01*
X486684Y700524D01*
X487252Y700145D01*
G01X492270Y696484D02*
X492744Y695979D01*
X493406Y695600D01*
X493975D01*
X494543Y695852D01*
X494921Y696231D01*
X495111Y696736D01*
X495016Y697494D01*
X494637Y697872D01*
X492933Y698630D01*
X492554Y699514D01*
X492744Y700145D01*
X493122Y700524D01*
X493690Y700650D01*
X494259Y700524D01*
X494827Y700145D01*
G01X499656Y700650D02*
Y697115D01*
X500035Y696231D01*
X500603Y695726D01*
X501265Y695600D01*
X501928Y695726D01*
X502496Y696231D01*
X502875Y697115D01*
G01Y695600D02*
Y700650D01*
G01X507420Y699009D02*
X510450D01*
X510166Y699893D01*
X509693Y700397D01*
X509030Y700650D01*
X508367Y700524D01*
X507799Y700145D01*
X507420Y699261D01*
X507231Y698504D01*
Y697746D01*
X507420Y696989D01*
X507894Y696231D01*
X508462Y695726D01*
X509125Y695600D01*
X509787Y695852D01*
X510450Y696610D01*
G01X516415Y695348D02*
X516226Y695474D01*
Y695726D01*
X516415Y695852D01*
X516605Y695726D01*
Y695474D01*
X516415Y695348D01*
G01Y698756D02*
X516226Y698882D01*
Y699135D01*
X516415Y699261D01*
X516605Y699135D01*
Y698882D01*
X516415Y698756D01*
G01X361340Y735000D02*
Y742575D01*
X360204Y741060D01*
G01Y735000D02*
X362477D01*
G01X368915D02*
Y742575D01*
X367779Y741060D01*
G01Y735000D02*
X370052D01*
G01X360840Y747500D02*
Y755075D01*
X359704Y753560D01*
G01Y747500D02*
X361977D01*
G01X368415Y755075D02*
X367658Y754823D01*
X367090Y754191D01*
X366711Y753434D01*
X366427Y752424D01*
X366332Y751287D01*
X366427Y750151D01*
X366711Y749141D01*
X367090Y748384D01*
X367658Y747752D01*
X368415Y747500D01*
X369173Y747752D01*
X369741Y748384D01*
X370120Y749141D01*
X370404Y750151D01*
X370499Y751287D01*
X370404Y752424D01*
X370120Y753434D01*
X369741Y754191D01*
X369173Y754823D01*
X368415Y755075D01*
G01X363731Y761384D02*
X364394Y760752D01*
X365151Y760500D01*
X365909Y760752D01*
X366571Y761510D01*
X367045Y762646D01*
X367234Y763782D01*
Y765171D01*
X367045Y766307D01*
X366571Y767317D01*
X366003Y767823D01*
X365340Y768075D01*
X364583Y767823D01*
X364015Y767317D01*
X363636Y766560D01*
X363447Y765550D01*
X363636Y764666D01*
X364110Y763782D01*
X364678Y763277D01*
X365340Y763151D01*
X366098Y763404D01*
X366666Y764035D01*
X367234Y765171D01*
G01X365151Y785000D02*
X365340Y786641D01*
X365625Y788030D01*
X366003Y789293D01*
X366477Y790681D01*
X367234Y792575D01*
X363447D01*
G01X365340Y773000D02*
X366003Y773126D01*
X366761Y773505D01*
X367234Y774136D01*
X367424Y775020D01*
X367234Y775904D01*
X366666Y776661D01*
X365814Y777040D01*
X364867D01*
X364299Y777293D01*
X363825Y777924D01*
X363636Y778807D01*
X363920Y779691D01*
X364583Y780323D01*
X365340Y780575D01*
X366098Y780323D01*
X366761Y779691D01*
X367045Y778807D01*
X366855Y777924D01*
X366382Y777293D01*
X365814Y777040D01*
X364867D01*
X364015Y776661D01*
X363447Y775904D01*
X363257Y775020D01*
X363447Y774136D01*
X363920Y773505D01*
X364678Y773126D01*
X365340Y773000D01*
G01X364041Y801156D02*
X364704Y802040D01*
X365272Y802545D01*
X366030Y802797D01*
X366693Y802545D01*
X367166Y802040D01*
X367545Y801282D01*
X367640Y800399D01*
X367545Y799641D01*
X367166Y798884D01*
X366598Y798252D01*
X365935Y798000D01*
X365178Y798252D01*
X364515Y799010D01*
X364136Y800146D01*
X364041Y801409D01*
X364231Y803050D01*
X364515Y803934D01*
X364988Y804817D01*
X365651Y805449D01*
X366314Y805575D01*
X366977Y805323D01*
X367450Y804691D01*
G01X366977Y836000D02*
Y843575D01*
X363473Y838146D01*
X368208D01*
G01X363757Y818636D02*
X364325Y818005D01*
X364988Y817626D01*
X365840Y817500D01*
X366693Y817752D01*
X367355Y818257D01*
X367829Y819141D01*
X367924Y820151D01*
X367734Y821161D01*
X367261Y821793D01*
X366598Y822297D01*
X365935Y822424D01*
X365272Y822297D01*
X364420Y821793D01*
X364704Y825075D01*
X367261D01*
G01X363757Y861515D02*
X364325Y860631D01*
X365083Y860126D01*
X365935Y860000D01*
X366693Y860126D01*
X367450Y860757D01*
X367924Y861515D01*
X368018Y862272D01*
X367829Y863156D01*
X367166Y863787D01*
X366503Y864040D01*
X365651D01*
G01X366503D02*
X367071Y864419D01*
X367545Y865050D01*
X367734Y865807D01*
X367545Y866565D01*
X367071Y867196D01*
X366219Y867575D01*
X365367Y867449D01*
X364515Y866944D01*
G01X364541Y879313D02*
X365110Y880070D01*
X365772Y880449D01*
X366530Y880575D01*
X367477Y880323D01*
X368140Y879691D01*
X368329Y878934D01*
X368234Y878176D01*
X367855Y877545D01*
X365962Y876282D01*
X365110Y875399D01*
X364541Y874136D01*
X364352Y873000D01*
X368329D01*
G01X366340Y885500D02*
Y893075D01*
X365204Y891560D01*
G01Y885500D02*
X367477D01*
G01X356663Y901000D02*
Y908575D01*
X361018Y901000D01*
Y908575D01*
G01X366415Y901000D02*
X365658Y901126D01*
X364995Y901631D01*
X364427Y902389D01*
X364048Y903272D01*
X363859Y904282D01*
Y905293D01*
X364048Y906303D01*
X364427Y907186D01*
X364995Y907944D01*
X365658Y908449D01*
X366415Y908575D01*
X367173Y908449D01*
X367836Y907944D01*
X368404Y907186D01*
X368783Y906303D01*
X368972Y905293D01*
Y904282D01*
X368783Y903272D01*
X368404Y902389D01*
X367836Y901631D01*
X367173Y901126D01*
X366415Y901000D01*
G01X373990Y900748D02*
X373801Y900874D01*
Y901126D01*
X373990Y901252D01*
X374180Y901126D01*
Y900874D01*
X373990Y900748D01*
G01X382852Y885000D02*
Y892575D01*
G01X386829D02*
Y885000D01*
G01Y888787D02*
X382852D01*
G01X392415Y885000D02*
X391847Y885126D01*
X391279Y885631D01*
X390900Y886515D01*
X390711Y887525D01*
X390900Y888535D01*
X391279Y889419D01*
X391847Y889924D01*
X392415Y890050D01*
X392984Y889924D01*
X393552Y889419D01*
X393930Y888535D01*
X394025Y887525D01*
X393930Y886515D01*
X393552Y885631D01*
X392984Y885126D01*
X392415Y885000D01*
G01X399990D02*
Y892575D01*
G01X406145Y888409D02*
X409175D01*
X408891Y889293D01*
X408418Y889797D01*
X407755Y890050D01*
X407092Y889924D01*
X406524Y889545D01*
X406145Y888661D01*
X405956Y887904D01*
Y887146D01*
X406145Y886389D01*
X406619Y885631D01*
X407187Y885126D01*
X407850Y885000D01*
X408512Y885252D01*
X409175Y886010D01*
G01X413040Y644675D02*
Y637100D01*
G01X410863Y644675D02*
X415218D01*
G01X419006Y637100D02*
Y644675D01*
G01Y641014D02*
X419479Y641645D01*
X419953Y642024D01*
X420710Y642150D01*
X421278Y642024D01*
X421941Y641519D01*
X422225Y640761D01*
Y637100D01*
G01X426770Y640509D02*
X429800D01*
X429516Y641393D01*
X429043Y641897D01*
X428380Y642150D01*
X427717Y642024D01*
X427149Y641645D01*
X426770Y640761D01*
X426581Y640004D01*
Y639246D01*
X426770Y638489D01*
X427244Y637731D01*
X427812Y637226D01*
X428475Y637100D01*
X429137Y637352D01*
X429800Y638110D01*
G01X434440Y637100D02*
Y642150D01*
G01Y641140D02*
X434913Y641645D01*
X435387Y642024D01*
X436050Y642150D01*
X436523Y642024D01*
X437091Y641645D01*
G01X441920Y640509D02*
X444950D01*
X444666Y641393D01*
X444193Y641897D01*
X443530Y642150D01*
X442867Y642024D01*
X442299Y641645D01*
X441920Y640761D01*
X441731Y640004D01*
Y639246D01*
X441920Y638489D01*
X442394Y637731D01*
X442962Y637226D01*
X443625Y637100D01*
X444287Y637352D01*
X444950Y638110D01*
G01X450347Y637100D02*
Y643539D01*
X450537Y644170D01*
X450915Y644549D01*
X451484Y644675D01*
X452052Y644423D01*
X452336Y643791D01*
G01X451200Y641645D02*
X449306D01*
G01X458490Y637100D02*
X457922Y637226D01*
X457354Y637731D01*
X456975Y638615D01*
X456786Y639625D01*
X456975Y640635D01*
X457354Y641519D01*
X457922Y642024D01*
X458490Y642150D01*
X459059Y642024D01*
X459627Y641519D01*
X460005Y640635D01*
X460100Y639625D01*
X460005Y638615D01*
X459627Y637731D01*
X459059Y637226D01*
X458490Y637100D01*
G01X464740D02*
Y642150D01*
G01Y641140D02*
X465213Y641645D01*
X465687Y642024D01*
X466350Y642150D01*
X466823Y642024D01*
X467391Y641645D01*
G01X472220Y640509D02*
X475250D01*
X474966Y641393D01*
X474493Y641897D01*
X473830Y642150D01*
X473167Y642024D01*
X472599Y641645D01*
X472220Y640761D01*
X472031Y640004D01*
Y639246D01*
X472220Y638489D01*
X472694Y637731D01*
X473262Y637226D01*
X473925Y637100D01*
X474587Y637352D01*
X475250Y638110D01*
G01X481026Y635711D02*
X481405Y637352D01*
G01X494661Y634575D02*
Y642150D01*
G01Y641014D02*
X495135Y641645D01*
X495608Y642024D01*
X496365Y642150D01*
X497028Y642024D01*
X497691Y641393D01*
X497975Y640509D01*
X498070Y639625D01*
X497975Y638741D01*
X497691Y637857D01*
X497123Y637352D01*
X496365Y637100D01*
X495703Y637226D01*
X495040Y637605D01*
X494661Y638110D01*
G01X503940Y637100D02*
Y644675D01*
G01X510095Y640509D02*
X513125D01*
X512841Y641393D01*
X512368Y641897D01*
X511705Y642150D01*
X511042Y642024D01*
X510474Y641645D01*
X510095Y640761D01*
X509906Y640004D01*
Y639246D01*
X510095Y638489D01*
X510569Y637731D01*
X511137Y637226D01*
X511800Y637100D01*
X512462Y637352D01*
X513125Y638110D01*
G01X520795Y637100D02*
Y642150D01*
G01Y641266D02*
X520416Y641771D01*
X519848Y642024D01*
X519185Y642150D01*
X518522Y641897D01*
X517954Y641393D01*
X517575Y640635D01*
X517386Y639625D01*
X517575Y638615D01*
X517954Y637857D01*
X518522Y637352D01*
X519185Y637100D01*
X519848Y637226D01*
X520416Y637605D01*
X520795Y638110D01*
G01X525245Y637984D02*
X525719Y637479D01*
X526381Y637100D01*
X526950D01*
X527518Y637352D01*
X527896Y637731D01*
X528086Y638236D01*
X527991Y638994D01*
X527612Y639372D01*
X525908Y640130D01*
X525529Y641014D01*
X525719Y641645D01*
X526097Y642024D01*
X526665Y642150D01*
X527234Y642024D01*
X527802Y641645D01*
G01X532820Y640509D02*
X535850D01*
X535566Y641393D01*
X535093Y641897D01*
X534430Y642150D01*
X533767Y642024D01*
X533199Y641645D01*
X532820Y640761D01*
X532631Y640004D01*
Y639246D01*
X532820Y638489D01*
X533294Y637731D01*
X533862Y637226D01*
X534525Y637100D01*
X535187Y637352D01*
X535850Y638110D01*
G01X548822Y637100D02*
Y643539D01*
X549012Y644170D01*
X549390Y644549D01*
X549959Y644675D01*
X550527Y644423D01*
X550811Y643791D01*
G01X549675Y641645D02*
X547781D01*
G01X556965Y637100D02*
X556397Y637226D01*
X555829Y637731D01*
X555450Y638615D01*
X555261Y639625D01*
X555450Y640635D01*
X555829Y641519D01*
X556397Y642024D01*
X556965Y642150D01*
X557534Y642024D01*
X558102Y641519D01*
X558480Y640635D01*
X558575Y639625D01*
X558480Y638615D01*
X558102Y637731D01*
X557534Y637226D01*
X556965Y637100D01*
G01X564540D02*
Y644675D01*
G01X572115Y637100D02*
Y644675D01*
G01X579690Y637100D02*
X579122Y637226D01*
X578554Y637731D01*
X578175Y638615D01*
X577986Y639625D01*
X578175Y640635D01*
X578554Y641519D01*
X579122Y642024D01*
X579690Y642150D01*
X580259Y642024D01*
X580827Y641519D01*
X581205Y640635D01*
X581300Y639625D01*
X581205Y638615D01*
X580827Y637731D01*
X580259Y637226D01*
X579690Y637100D01*
G01X584898Y642150D02*
X586035Y637100D01*
X587265Y642150D01*
X588496Y637100D01*
X589633Y642150D01*
G01X600332Y638615D02*
X600900Y637731D01*
X601658Y637226D01*
X602510Y637100D01*
X603268Y637226D01*
X604025Y637857D01*
X604499Y638615D01*
X604593Y639372D01*
X604404Y640256D01*
X603741Y640887D01*
X603078Y641140D01*
X602226D01*
G01X603078D02*
X603646Y641519D01*
X604120Y642150D01*
X604309Y642907D01*
X604120Y643665D01*
X603646Y644296D01*
X602794Y644675D01*
X601942Y644549D01*
X601090Y644044D01*
G01X609990Y636848D02*
X609801Y636974D01*
Y637226D01*
X609990Y637352D01*
X610180Y637226D01*
Y636974D01*
X609990Y636848D01*
G01X617565Y637100D02*
Y644675D01*
X616429Y643160D01*
G01Y637100D02*
X618702D01*
G01X625140D02*
X625803Y637226D01*
X626561Y637605D01*
X627034Y638236D01*
X627224Y639120D01*
X627034Y640004D01*
X626466Y640761D01*
X625614Y641140D01*
X624667D01*
X624099Y641393D01*
X623625Y642024D01*
X623436Y642907D01*
X623720Y643791D01*
X624383Y644423D01*
X625140Y644675D01*
X625898Y644423D01*
X626561Y643791D01*
X626845Y642907D01*
X626655Y642024D01*
X626182Y641393D01*
X625614Y641140D01*
X624667D01*
X623815Y640761D01*
X623247Y640004D01*
X623057Y639120D01*
X623247Y638236D01*
X623720Y637605D01*
X624478Y637226D01*
X625140Y637100D01*
G01X629875D02*
Y642150D01*
G01Y640761D02*
X630159Y641393D01*
X630632Y641897D01*
X631295Y642150D01*
X631958Y641897D01*
X632431Y641393D01*
X632715Y640761D01*
Y637100D01*
G01Y640761D02*
X633000Y641393D01*
X633473Y641897D01*
X634136Y642150D01*
X634799Y641897D01*
X635272Y641393D01*
X635556Y640635D01*
Y637100D01*
G01X637450D02*
Y642150D01*
G01Y640761D02*
X637734Y641393D01*
X638207Y641897D01*
X638870Y642150D01*
X639533Y641897D01*
X640006Y641393D01*
X640290Y640761D01*
Y637100D01*
G01Y640761D02*
X640575Y641393D01*
X641048Y641897D01*
X641711Y642150D01*
X642374Y641897D01*
X642847Y641393D01*
X643131Y640635D01*
Y637100D01*
G01X655440Y644675D02*
Y637100D01*
G01X654115Y642150D02*
X656766D01*
G01X663015Y637100D02*
X662447Y637226D01*
X661879Y637731D01*
X661500Y638615D01*
X661311Y639625D01*
X661500Y640635D01*
X661879Y641519D01*
X662447Y642024D01*
X663015Y642150D01*
X663584Y642024D01*
X664152Y641519D01*
X664530Y640635D01*
X664625Y639625D01*
X664530Y638615D01*
X664152Y637731D01*
X663584Y637226D01*
X663015Y637100D01*
G01X676461Y634575D02*
Y642150D01*
G01Y641014D02*
X676935Y641645D01*
X677408Y642024D01*
X678165Y642150D01*
X678828Y642024D01*
X679491Y641393D01*
X679775Y640509D01*
X679870Y639625D01*
X679775Y638741D01*
X679491Y637857D01*
X678923Y637352D01*
X678165Y637100D01*
X677503Y637226D01*
X676840Y637605D01*
X676461Y638110D01*
G01X684415Y637100D02*
Y642150D01*
G01Y641140D02*
X684888Y641645D01*
X685362Y642024D01*
X686025Y642150D01*
X686498Y642024D01*
X687066Y641645D01*
G01X693315Y637100D02*
X692747Y637226D01*
X692179Y637731D01*
X691800Y638615D01*
X691611Y639625D01*
X691800Y640635D01*
X692179Y641519D01*
X692747Y642024D01*
X693315Y642150D01*
X693884Y642024D01*
X694452Y641519D01*
X694830Y640635D01*
X694925Y639625D01*
X694830Y638615D01*
X694452Y637731D01*
X693884Y637226D01*
X693315Y637100D01*
G01X702595Y644675D02*
Y637100D01*
G01Y638236D02*
X702216Y637605D01*
X701648Y637226D01*
X700985Y637100D01*
X700228Y637352D01*
X699660Y637984D01*
X699281Y638741D01*
X699186Y639625D01*
X699281Y640509D01*
X699660Y641266D01*
X700228Y641897D01*
X700985Y642150D01*
X701648Y642024D01*
X702121Y641771D01*
X702595Y641266D01*
G01X706856Y642150D02*
Y638615D01*
X707235Y637731D01*
X707803Y637226D01*
X708465Y637100D01*
X709128Y637226D01*
X709696Y637731D01*
X710075Y638615D01*
G01Y637100D02*
Y642150D01*
G01X717555Y641519D02*
X716893Y642024D01*
X716325Y642150D01*
X715567Y641897D01*
X714999Y641393D01*
X714620Y640509D01*
X714525Y639625D01*
X714620Y638741D01*
X714999Y637984D01*
X715567Y637352D01*
X716325Y637100D01*
X716987Y637352D01*
X717555Y637857D01*
G01X722195Y640509D02*
X725225D01*
X724941Y641393D01*
X724468Y641897D01*
X723805Y642150D01*
X723142Y642024D01*
X722574Y641645D01*
X722195Y640761D01*
X722006Y640004D01*
Y639246D01*
X722195Y638489D01*
X722669Y637731D01*
X723237Y637226D01*
X723900Y637100D01*
X724562Y637352D01*
X725225Y638110D01*
G01X738765Y644675D02*
Y637100D01*
G01X737440Y642150D02*
X740091D01*
G01X744731Y637100D02*
Y644675D01*
G01Y641014D02*
X745204Y641645D01*
X745678Y642024D01*
X746435Y642150D01*
X747003Y642024D01*
X747666Y641519D01*
X747950Y640761D01*
Y637100D01*
G01X753915Y642150D02*
Y637100D01*
G01Y644170D02*
X753726Y644296D01*
Y644549D01*
X753915Y644675D01*
X754105Y644549D01*
Y644296D01*
X753915Y644170D01*
G01X760070Y637984D02*
X760544Y637479D01*
X761206Y637100D01*
X761775D01*
X762343Y637352D01*
X762721Y637731D01*
X762911Y638236D01*
X762816Y638994D01*
X762437Y639372D01*
X760733Y640130D01*
X760354Y641014D01*
X760544Y641645D01*
X760922Y642024D01*
X761490Y642150D01*
X762059Y642024D01*
X762627Y641645D01*
G01X774936Y637100D02*
Y644675D01*
G01Y640887D02*
X775410Y641645D01*
X775978Y642024D01*
X776546Y642150D01*
X777398Y641897D01*
X777966Y641393D01*
X778345Y640509D01*
Y639499D01*
X778155Y638489D01*
X777777Y637731D01*
X777114Y637226D01*
X776546Y637100D01*
X775978Y637226D01*
X775410Y637605D01*
X774936Y638236D01*
G01X784215Y637100D02*
X783647Y637226D01*
X783079Y637731D01*
X782700Y638615D01*
X782511Y639625D01*
X782700Y640635D01*
X783079Y641519D01*
X783647Y642024D01*
X784215Y642150D01*
X784784Y642024D01*
X785352Y641519D01*
X785730Y640635D01*
X785825Y639625D01*
X785730Y638615D01*
X785352Y637731D01*
X784784Y637226D01*
X784215Y637100D01*
G01X793495D02*
Y642150D01*
G01Y641266D02*
X793116Y641771D01*
X792548Y642024D01*
X791885Y642150D01*
X791222Y641897D01*
X790654Y641393D01*
X790275Y640635D01*
X790086Y639625D01*
X790275Y638615D01*
X790654Y637857D01*
X791222Y637352D01*
X791885Y637100D01*
X792548Y637226D01*
X793116Y637605D01*
X793495Y638110D01*
G01X798040Y637100D02*
Y642150D01*
G01Y641140D02*
X798513Y641645D01*
X798987Y642024D01*
X799650Y642150D01*
X800123Y642024D01*
X800691Y641645D01*
G01X808645Y644675D02*
Y637100D01*
G01Y638236D02*
X808266Y637605D01*
X807698Y637226D01*
X807035Y637100D01*
X806278Y637352D01*
X805710Y637984D01*
X805331Y638741D01*
X805236Y639625D01*
X805331Y640509D01*
X805710Y641266D01*
X806278Y641897D01*
X807035Y642150D01*
X807698Y642024D01*
X808171Y641771D01*
X808645Y641266D01*
G01X814515Y636848D02*
X814326Y636974D01*
Y637226D01*
X814515Y637352D01*
X814705Y637226D01*
Y636974D01*
X814515Y636848D01*
G01X412840Y654675D02*
Y647100D01*
G01X410663Y654675D02*
X415018D01*
G01X418806Y647100D02*
Y654675D01*
G01Y651014D02*
X419279Y651645D01*
X419753Y652024D01*
X420510Y652150D01*
X421078Y652024D01*
X421741Y651519D01*
X422025Y650761D01*
Y647100D01*
G01X426570Y650509D02*
X429600D01*
X429316Y651393D01*
X428843Y651897D01*
X428180Y652150D01*
X427517Y652024D01*
X426949Y651645D01*
X426570Y650761D01*
X426381Y650004D01*
Y649246D01*
X426570Y648489D01*
X427044Y647731D01*
X427612Y647226D01*
X428275Y647100D01*
X428937Y647352D01*
X429600Y648110D01*
G01X433956Y647100D02*
Y652150D01*
G01Y650887D02*
X434335Y651519D01*
X434903Y652024D01*
X435660Y652150D01*
X436323Y652024D01*
X436891Y651519D01*
X437175Y650635D01*
Y647100D01*
G01X452230Y651519D02*
X451568Y652024D01*
X451000Y652150D01*
X450242Y651897D01*
X449674Y651393D01*
X449295Y650509D01*
X449200Y649625D01*
X449295Y648741D01*
X449674Y647984D01*
X450242Y647352D01*
X451000Y647100D01*
X451662Y647352D01*
X452230Y647857D01*
G01X458290Y647100D02*
X457722Y647226D01*
X457154Y647731D01*
X456775Y648615D01*
X456586Y649625D01*
X456775Y650635D01*
X457154Y651519D01*
X457722Y652024D01*
X458290Y652150D01*
X458859Y652024D01*
X459427Y651519D01*
X459805Y650635D01*
X459900Y649625D01*
X459805Y648615D01*
X459427Y647731D01*
X458859Y647226D01*
X458290Y647100D01*
G01X464256D02*
Y652150D01*
G01Y650887D02*
X464635Y651519D01*
X465203Y652024D01*
X465960Y652150D01*
X466623Y652024D01*
X467191Y651519D01*
X467475Y650635D01*
Y647100D01*
G01X471736Y652150D02*
X473440Y647100D01*
X475145Y652150D01*
G01X479595Y650509D02*
X482625D01*
X482341Y651393D01*
X481868Y651897D01*
X481205Y652150D01*
X480542Y652024D01*
X479974Y651645D01*
X479595Y650761D01*
X479406Y650004D01*
Y649246D01*
X479595Y648489D01*
X480069Y647731D01*
X480637Y647226D01*
X481300Y647100D01*
X481962Y647352D01*
X482625Y648110D01*
G01X487265Y647100D02*
Y652150D01*
G01Y651140D02*
X487738Y651645D01*
X488212Y652024D01*
X488875Y652150D01*
X489348Y652024D01*
X489916Y651645D01*
G01X496165Y654675D02*
Y647100D01*
G01X494840Y652150D02*
X497491D01*
G01X509232Y648615D02*
X509800Y647731D01*
X510558Y647226D01*
X511410Y647100D01*
X512168Y647226D01*
X512925Y647857D01*
X513399Y648615D01*
X513493Y649372D01*
X513304Y650256D01*
X512641Y650887D01*
X511978Y651140D01*
X511126D01*
G01X511978D02*
X512546Y651519D01*
X513020Y652150D01*
X513209Y652907D01*
X513020Y653665D01*
X512546Y654296D01*
X511694Y654675D01*
X510842Y654549D01*
X509990Y654044D01*
G01X518890Y646848D02*
X518701Y646974D01*
Y647226D01*
X518890Y647352D01*
X519080Y647226D01*
Y646974D01*
X518890Y646848D01*
G01X526465Y647100D02*
Y654675D01*
X525329Y653160D01*
G01Y647100D02*
X527602D01*
G01X534040D02*
X534703Y647226D01*
X535461Y647605D01*
X535934Y648236D01*
X536124Y649120D01*
X535934Y650004D01*
X535366Y650761D01*
X534514Y651140D01*
X533567D01*
X532999Y651393D01*
X532525Y652024D01*
X532336Y652907D01*
X532620Y653791D01*
X533283Y654423D01*
X534040Y654675D01*
X534798Y654423D01*
X535461Y653791D01*
X535745Y652907D01*
X535555Y652024D01*
X535082Y651393D01*
X534514Y651140D01*
X533567D01*
X532715Y650761D01*
X532147Y650004D01*
X531957Y649120D01*
X532147Y648236D01*
X532620Y647605D01*
X533378Y647226D01*
X534040Y647100D01*
G01X538775D02*
Y652150D01*
G01Y650761D02*
X539059Y651393D01*
X539532Y651897D01*
X540195Y652150D01*
X540858Y651897D01*
X541331Y651393D01*
X541615Y650761D01*
Y647100D01*
G01Y650761D02*
X541900Y651393D01*
X542373Y651897D01*
X543036Y652150D01*
X543699Y651897D01*
X544172Y651393D01*
X544456Y650635D01*
Y647100D01*
G01X546350D02*
Y652150D01*
G01Y650761D02*
X546634Y651393D01*
X547107Y651897D01*
X547770Y652150D01*
X548433Y651897D01*
X548906Y651393D01*
X549190Y650761D01*
Y647100D01*
G01Y650761D02*
X549475Y651393D01*
X549948Y651897D01*
X550611Y652150D01*
X551274Y651897D01*
X551747Y651393D01*
X552031Y650635D01*
Y647100D01*
G01X564340Y652150D02*
Y647100D01*
G01Y654170D02*
X564151Y654296D01*
Y654549D01*
X564340Y654675D01*
X564530Y654549D01*
Y654296D01*
X564340Y654170D01*
G01X570306Y647100D02*
Y652150D01*
G01Y650887D02*
X570685Y651519D01*
X571253Y652024D01*
X572010Y652150D01*
X572673Y652024D01*
X573241Y651519D01*
X573525Y650635D01*
Y647100D01*
G01X579490Y654675D02*
Y647100D01*
G01X578165Y652150D02*
X580816D01*
G01X587065Y647100D02*
X586497Y647226D01*
X585929Y647731D01*
X585550Y648615D01*
X585361Y649625D01*
X585550Y650635D01*
X585929Y651519D01*
X586497Y652024D01*
X587065Y652150D01*
X587634Y652024D01*
X588202Y651519D01*
X588580Y650635D01*
X588675Y649625D01*
X588580Y648615D01*
X588202Y647731D01*
X587634Y647226D01*
X587065Y647100D01*
G01X602215D02*
Y654675D01*
X601079Y653160D01*
G01Y647100D02*
X603352D01*
G01X607991Y653413D02*
X608560Y654170D01*
X609222Y654549D01*
X609980Y654675D01*
X610927Y654423D01*
X611590Y653791D01*
X611779Y653034D01*
X611684Y652276D01*
X611305Y651645D01*
X609412Y650382D01*
X608560Y649499D01*
X607991Y648236D01*
X607802Y647100D01*
X611779D01*
G01X615282Y648236D02*
X615850Y647605D01*
X616513Y647226D01*
X617365Y647100D01*
X618218Y647352D01*
X618880Y647857D01*
X619354Y648741D01*
X619449Y649751D01*
X619259Y650761D01*
X618786Y651393D01*
X618123Y651897D01*
X617460Y652024D01*
X616797Y651897D01*
X615945Y651393D01*
X616229Y654675D01*
X618786D01*
G01X624940Y646848D02*
X624751Y646974D01*
Y647226D01*
X624940Y647352D01*
X625130Y647226D01*
Y646974D01*
X624940Y646848D01*
G01X632515Y647100D02*
Y654675D01*
X631379Y653160D01*
G01Y647100D02*
X633652D01*
G01X638481Y647984D02*
X639144Y647352D01*
X639901Y647100D01*
X640659Y647352D01*
X641321Y648110D01*
X641795Y649246D01*
X641984Y650382D01*
Y651771D01*
X641795Y652907D01*
X641321Y653917D01*
X640753Y654423D01*
X640090Y654675D01*
X639333Y654423D01*
X638765Y653917D01*
X638386Y653160D01*
X638197Y652150D01*
X638386Y651266D01*
X638860Y650382D01*
X639428Y649877D01*
X640090Y649751D01*
X640848Y650004D01*
X641416Y650635D01*
X641984Y651771D01*
G01X645866Y650256D02*
X646529Y651140D01*
X647097Y651645D01*
X647855Y651897D01*
X648518Y651645D01*
X648991Y651140D01*
X649370Y650382D01*
X649465Y649499D01*
X649370Y648741D01*
X648991Y647984D01*
X648423Y647352D01*
X647760Y647100D01*
X647003Y647352D01*
X646340Y648110D01*
X645961Y649246D01*
X645866Y650509D01*
X646056Y652150D01*
X646340Y653034D01*
X646813Y653917D01*
X647476Y654549D01*
X648139Y654675D01*
X648802Y654423D01*
X649275Y653791D01*
G01X655240Y647100D02*
X655903Y647226D01*
X656661Y647605D01*
X657134Y648236D01*
X657324Y649120D01*
X657134Y650004D01*
X656566Y650761D01*
X655714Y651140D01*
X654767D01*
X654199Y651393D01*
X653725Y652024D01*
X653536Y652907D01*
X653820Y653791D01*
X654483Y654423D01*
X655240Y654675D01*
X655998Y654423D01*
X656661Y653791D01*
X656945Y652907D01*
X656755Y652024D01*
X656282Y651393D01*
X655714Y651140D01*
X654767D01*
X653915Y650761D01*
X653347Y650004D01*
X653157Y649120D01*
X653347Y648236D01*
X653820Y647605D01*
X654578Y647226D01*
X655240Y647100D01*
G01X659975D02*
Y652150D01*
G01Y650761D02*
X660259Y651393D01*
X660732Y651897D01*
X661395Y652150D01*
X662058Y651897D01*
X662531Y651393D01*
X662815Y650761D01*
Y647100D01*
G01Y650761D02*
X663100Y651393D01*
X663573Y651897D01*
X664236Y652150D01*
X664899Y651897D01*
X665372Y651393D01*
X665656Y650635D01*
Y647100D01*
G01X670390Y652150D02*
Y647100D01*
G01Y654170D02*
X670201Y654296D01*
Y654549D01*
X670390Y654675D01*
X670580Y654549D01*
Y654296D01*
X670390Y654170D01*
G01X677965Y647100D02*
Y654675D01*
G01X685351Y645711D02*
X685730Y647352D01*
G01X700690Y654675D02*
Y647100D01*
G01X699365Y652150D02*
X702016D01*
G01X706656Y647100D02*
Y654675D01*
G01Y651014D02*
X707129Y651645D01*
X707603Y652024D01*
X708360Y652150D01*
X708928Y652024D01*
X709591Y651519D01*
X709875Y650761D01*
Y647100D01*
G01X714420Y650509D02*
X717450D01*
X717166Y651393D01*
X716693Y651897D01*
X716030Y652150D01*
X715367Y652024D01*
X714799Y651645D01*
X714420Y650761D01*
X714231Y650004D01*
Y649246D01*
X714420Y648489D01*
X714894Y647731D01*
X715462Y647226D01*
X716125Y647100D01*
X716787Y647352D01*
X717450Y648110D01*
G01X732695Y654675D02*
Y647100D01*
G01Y648236D02*
X732316Y647605D01*
X731748Y647226D01*
X731085Y647100D01*
X730328Y647352D01*
X729760Y647984D01*
X729381Y648741D01*
X729286Y649625D01*
X729381Y650509D01*
X729760Y651266D01*
X730328Y651897D01*
X731085Y652150D01*
X731748Y652024D01*
X732221Y651771D01*
X732695Y651266D01*
G01X738565Y652150D02*
Y647100D01*
G01Y654170D02*
X738376Y654296D01*
Y654549D01*
X738565Y654675D01*
X738755Y654549D01*
Y654296D01*
X738565Y654170D01*
G01X745572Y647100D02*
Y653539D01*
X745762Y654170D01*
X746140Y654549D01*
X746709Y654675D01*
X747277Y654423D01*
X747561Y653791D01*
G01X746425Y651645D02*
X744531D01*
G01X753147Y647100D02*
Y653539D01*
X753337Y654170D01*
X753715Y654549D01*
X754284Y654675D01*
X754852Y654423D01*
X755136Y653791D01*
G01X754000Y651645D02*
X752106D01*
G01X759870Y650509D02*
X762900D01*
X762616Y651393D01*
X762143Y651897D01*
X761480Y652150D01*
X760817Y652024D01*
X760249Y651645D01*
X759870Y650761D01*
X759681Y650004D01*
Y649246D01*
X759870Y648489D01*
X760344Y647731D01*
X760912Y647226D01*
X761575Y647100D01*
X762237Y647352D01*
X762900Y648110D01*
G01X767540Y647100D02*
Y652150D01*
G01Y651140D02*
X768013Y651645D01*
X768487Y652024D01*
X769150Y652150D01*
X769623Y652024D01*
X770191Y651645D01*
G01X775020Y650509D02*
X778050D01*
X777766Y651393D01*
X777293Y651897D01*
X776630Y652150D01*
X775967Y652024D01*
X775399Y651645D01*
X775020Y650761D01*
X774831Y650004D01*
Y649246D01*
X775020Y648489D01*
X775494Y647731D01*
X776062Y647226D01*
X776725Y647100D01*
X777387Y647352D01*
X778050Y648110D01*
G01X782406Y647100D02*
Y652150D01*
G01Y650887D02*
X782785Y651519D01*
X783353Y652024D01*
X784110Y652150D01*
X784773Y652024D01*
X785341Y651519D01*
X785625Y650635D01*
Y647100D01*
G01X793105Y651519D02*
X792443Y652024D01*
X791875Y652150D01*
X791117Y651897D01*
X790549Y651393D01*
X790170Y650509D01*
X790075Y649625D01*
X790170Y648741D01*
X790549Y647984D01*
X791117Y647352D01*
X791875Y647100D01*
X792537Y647352D01*
X793105Y647857D01*
G01X797745Y650509D02*
X800775D01*
X800491Y651393D01*
X800018Y651897D01*
X799355Y652150D01*
X798692Y652024D01*
X798124Y651645D01*
X797745Y650761D01*
X797556Y650004D01*
Y649246D01*
X797745Y648489D01*
X798219Y647731D01*
X798787Y647226D01*
X799450Y647100D01*
X800112Y647352D01*
X800775Y648110D01*
G01X812611Y647100D02*
Y654675D01*
G01Y650887D02*
X813085Y651645D01*
X813653Y652024D01*
X814221Y652150D01*
X815073Y651897D01*
X815641Y651393D01*
X816020Y650509D01*
Y649499D01*
X815830Y648489D01*
X815452Y647731D01*
X814789Y647226D01*
X814221Y647100D01*
X813653Y647226D01*
X813085Y647605D01*
X812611Y648236D01*
G01X820470Y650509D02*
X823500D01*
X823216Y651393D01*
X822743Y651897D01*
X822080Y652150D01*
X821417Y652024D01*
X820849Y651645D01*
X820470Y650761D01*
X820281Y650004D01*
Y649246D01*
X820470Y648489D01*
X820944Y647731D01*
X821512Y647226D01*
X822175Y647100D01*
X822837Y647352D01*
X823500Y648110D01*
G01X829465Y654675D02*
Y647100D01*
G01X828140Y652150D02*
X830791D01*
G01X834673D02*
X835810Y647100D01*
X837040Y652150D01*
X838271Y647100D01*
X839408Y652150D01*
G01X843195Y650509D02*
X846225D01*
X845941Y651393D01*
X845468Y651897D01*
X844805Y652150D01*
X844142Y652024D01*
X843574Y651645D01*
X843195Y650761D01*
X843006Y650004D01*
Y649246D01*
X843195Y648489D01*
X843669Y647731D01*
X844237Y647226D01*
X844900Y647100D01*
X845562Y647352D01*
X846225Y648110D01*
G01X850770Y650509D02*
X853800D01*
X853516Y651393D01*
X853043Y651897D01*
X852380Y652150D01*
X851717Y652024D01*
X851149Y651645D01*
X850770Y650761D01*
X850581Y650004D01*
Y649246D01*
X850770Y648489D01*
X851244Y647731D01*
X851812Y647226D01*
X852475Y647100D01*
X853137Y647352D01*
X853800Y648110D01*
G01X858156Y647100D02*
Y652150D01*
G01Y650887D02*
X858535Y651519D01*
X859103Y652024D01*
X859860Y652150D01*
X860523Y652024D01*
X861091Y651519D01*
X861375Y650635D01*
Y647100D01*
G01X874915D02*
Y654675D01*
X873779Y653160D01*
G01Y647100D02*
X876052D01*
G01X880691Y653413D02*
X881260Y654170D01*
X881922Y654549D01*
X882680Y654675D01*
X883627Y654423D01*
X884290Y653791D01*
X884479Y653034D01*
X884384Y652276D01*
X884005Y651645D01*
X882112Y650382D01*
X881260Y649499D01*
X880691Y648236D01*
X880502Y647100D01*
X884479D01*
G01X888266Y650256D02*
X888929Y651140D01*
X889497Y651645D01*
X890255Y651897D01*
X890918Y651645D01*
X891391Y651140D01*
X891770Y650382D01*
X891865Y649499D01*
X891770Y648741D01*
X891391Y647984D01*
X890823Y647352D01*
X890160Y647100D01*
X889403Y647352D01*
X888740Y648110D01*
X888361Y649246D01*
X888266Y650509D01*
X888456Y652150D01*
X888740Y653034D01*
X889213Y653917D01*
X889876Y654549D01*
X890539Y654675D01*
X891202Y654423D01*
X891675Y653791D01*
G01X894800Y647100D02*
Y652150D01*
G01Y650761D02*
X895084Y651393D01*
X895557Y651897D01*
X896220Y652150D01*
X896883Y651897D01*
X897356Y651393D01*
X897640Y650761D01*
Y647100D01*
G01Y650761D02*
X897925Y651393D01*
X898398Y651897D01*
X899061Y652150D01*
X899724Y651897D01*
X900197Y651393D01*
X900481Y650635D01*
Y647100D01*
G01X905215Y652150D02*
Y647100D01*
G01Y654170D02*
X905026Y654296D01*
Y654549D01*
X905215Y654675D01*
X905405Y654549D01*
Y654296D01*
X905215Y654170D01*
G01X912790Y647100D02*
Y654675D01*
G01X929645Y647100D02*
Y652150D01*
G01Y651266D02*
X929266Y651771D01*
X928698Y652024D01*
X928035Y652150D01*
X927372Y651897D01*
X926804Y651393D01*
X926425Y650635D01*
X926236Y649625D01*
X926425Y648615D01*
X926804Y647857D01*
X927372Y647352D01*
X928035Y647100D01*
X928698Y647226D01*
X929266Y647605D01*
X929645Y648110D01*
G01X933906Y647100D02*
Y652150D01*
G01Y650887D02*
X934285Y651519D01*
X934853Y652024D01*
X935610Y652150D01*
X936273Y652024D01*
X936841Y651519D01*
X937125Y650635D01*
Y647100D01*
G01X944795Y654675D02*
Y647100D01*
G01Y648236D02*
X944416Y647605D01*
X943848Y647226D01*
X943185Y647100D01*
X942428Y647352D01*
X941860Y647984D01*
X941481Y648741D01*
X941386Y649625D01*
X941481Y650509D01*
X941860Y651266D01*
X942428Y651897D01*
X943185Y652150D01*
X943848Y652024D01*
X944321Y651771D01*
X944795Y651266D01*
G01X958240Y647100D02*
Y654675D01*
X957104Y653160D01*
G01Y647100D02*
X959377D01*
G01X964016Y653413D02*
X964585Y654170D01*
X965247Y654549D01*
X966005Y654675D01*
X966952Y654423D01*
X967615Y653791D01*
X967804Y653034D01*
X967709Y652276D01*
X967330Y651645D01*
X965437Y650382D01*
X964585Y649499D01*
X964016Y648236D01*
X963827Y647100D01*
X967804D01*
G01X971307Y648236D02*
X971875Y647605D01*
X972538Y647226D01*
X973390Y647100D01*
X974243Y647352D01*
X974905Y647857D01*
X975379Y648741D01*
X975474Y649751D01*
X975284Y650761D01*
X974811Y651393D01*
X974148Y651897D01*
X973485Y652024D01*
X972822Y651897D01*
X971970Y651393D01*
X972254Y654675D01*
X974811D01*
G01X980965Y646848D02*
X980776Y646974D01*
Y647226D01*
X980965Y647352D01*
X981155Y647226D01*
Y646974D01*
X980965Y646848D01*
G01X988540Y647100D02*
Y654675D01*
X987404Y653160D01*
G01Y647100D02*
X989677D01*
G01X994506Y647984D02*
X995169Y647352D01*
X995926Y647100D01*
X996684Y647352D01*
X997346Y648110D01*
X997820Y649246D01*
X998009Y650382D01*
Y651771D01*
X997820Y652907D01*
X997346Y653917D01*
X996778Y654423D01*
X996115Y654675D01*
X995358Y654423D01*
X994790Y653917D01*
X994411Y653160D01*
X994222Y652150D01*
X994411Y651266D01*
X994885Y650382D01*
X995453Y649877D01*
X996115Y649751D01*
X996873Y650004D01*
X997441Y650635D01*
X998009Y651771D01*
G01X1001891Y650256D02*
X1002554Y651140D01*
X1003122Y651645D01*
X1003880Y651897D01*
X1004543Y651645D01*
X1005016Y651140D01*
X1005395Y650382D01*
X1005490Y649499D01*
X1005395Y648741D01*
X1005016Y647984D01*
X1004448Y647352D01*
X1003785Y647100D01*
X1003028Y647352D01*
X1002365Y648110D01*
X1001986Y649246D01*
X1001891Y650509D01*
X1002081Y652150D01*
X1002365Y653034D01*
X1002838Y653917D01*
X1003501Y654549D01*
X1004164Y654675D01*
X1004827Y654423D01*
X1005300Y653791D01*
G01X1011265Y647100D02*
X1011928Y647226D01*
X1012686Y647605D01*
X1013159Y648236D01*
X1013349Y649120D01*
X1013159Y650004D01*
X1012591Y650761D01*
X1011739Y651140D01*
X1010792D01*
X1010224Y651393D01*
X1009750Y652024D01*
X1009561Y652907D01*
X1009845Y653791D01*
X1010508Y654423D01*
X1011265Y654675D01*
X1012023Y654423D01*
X1012686Y653791D01*
X1012970Y652907D01*
X1012780Y652024D01*
X1012307Y651393D01*
X1011739Y651140D01*
X1010792D01*
X1009940Y650761D01*
X1009372Y650004D01*
X1009182Y649120D01*
X1009372Y648236D01*
X1009845Y647605D01*
X1010603Y647226D01*
X1011265Y647100D01*
G01X1026415Y652150D02*
Y647100D01*
G01Y654170D02*
X1026226Y654296D01*
Y654549D01*
X1026415Y654675D01*
X1026605Y654549D01*
Y654296D01*
X1026415Y654170D01*
G01X1032570Y647984D02*
X1033044Y647479D01*
X1033706Y647100D01*
X1034275D01*
X1034843Y647352D01*
X1035221Y647731D01*
X1035411Y648236D01*
X1035316Y648994D01*
X1034937Y649372D01*
X1033233Y650130D01*
X1032854Y651014D01*
X1033044Y651645D01*
X1033422Y652024D01*
X1033990Y652150D01*
X1034559Y652024D01*
X1035127Y651645D01*
G01X1049140Y647100D02*
Y654675D01*
G01X1055295Y650509D02*
X1058325D01*
X1058041Y651393D01*
X1057568Y651897D01*
X1056905Y652150D01*
X1056242Y652024D01*
X1055674Y651645D01*
X1055295Y650761D01*
X1055106Y650004D01*
Y649246D01*
X1055295Y648489D01*
X1055769Y647731D01*
X1056337Y647226D01*
X1057000Y647100D01*
X1057662Y647352D01*
X1058325Y648110D01*
G01X1062870Y647984D02*
X1063344Y647479D01*
X1064006Y647100D01*
X1064575D01*
X1065143Y647352D01*
X1065521Y647731D01*
X1065711Y648236D01*
X1065616Y648994D01*
X1065237Y649372D01*
X1063533Y650130D01*
X1063154Y651014D01*
X1063344Y651645D01*
X1063722Y652024D01*
X1064290Y652150D01*
X1064859Y652024D01*
X1065427Y651645D01*
G01X1070445Y647984D02*
X1070919Y647479D01*
X1071581Y647100D01*
X1072150D01*
X1072718Y647352D01*
X1073096Y647731D01*
X1073286Y648236D01*
X1073191Y648994D01*
X1072812Y649372D01*
X1071108Y650130D01*
X1070729Y651014D01*
X1070919Y651645D01*
X1071297Y652024D01*
X1071865Y652150D01*
X1072434Y652024D01*
X1073002Y651645D01*
G01X1087015Y654675D02*
Y647100D01*
G01X1085690Y652150D02*
X1088341D01*
G01X1092981Y647100D02*
Y654675D01*
G01Y651014D02*
X1093454Y651645D01*
X1093928Y652024D01*
X1094685Y652150D01*
X1095253Y652024D01*
X1095916Y651519D01*
X1096200Y650761D01*
Y647100D01*
G01X1103870D02*
Y652150D01*
G01Y651266D02*
X1103491Y651771D01*
X1102923Y652024D01*
X1102260Y652150D01*
X1101597Y651897D01*
X1101029Y651393D01*
X1100650Y650635D01*
X1100461Y649625D01*
X1100650Y648615D01*
X1101029Y647857D01*
X1101597Y647352D01*
X1102260Y647100D01*
X1102923Y647226D01*
X1103491Y647605D01*
X1103870Y648110D01*
G01X1108131Y647100D02*
Y652150D01*
G01Y650887D02*
X1108510Y651519D01*
X1109078Y652024D01*
X1109835Y652150D01*
X1110498Y652024D01*
X1111066Y651519D01*
X1111350Y650635D01*
Y647100D01*
G01X1124890D02*
Y654675D01*
X1123754Y653160D01*
G01Y647100D02*
X1126027D01*
G01X1137200D02*
Y652150D01*
G01Y650761D02*
X1137484Y651393D01*
X1137957Y651897D01*
X1138620Y652150D01*
X1139283Y651897D01*
X1139756Y651393D01*
X1140040Y650761D01*
Y647100D01*
G01Y650761D02*
X1140325Y651393D01*
X1140798Y651897D01*
X1141461Y652150D01*
X1142124Y651897D01*
X1142597Y651393D01*
X1142881Y650635D01*
Y647100D01*
G01X1147615Y652150D02*
Y647100D01*
G01Y654170D02*
X1147426Y654296D01*
Y654549D01*
X1147615Y654675D01*
X1147805Y654549D01*
Y654296D01*
X1147615Y654170D01*
G01X1155190Y647100D02*
Y654675D01*
G01X1162576Y645711D02*
X1162955Y647352D01*
G01X398447Y735500D02*
Y743075D01*
X400814D01*
X401571Y742696D01*
X402045Y742191D01*
X402234Y741181D01*
X402045Y740171D01*
X401477Y739540D01*
X400814Y739161D01*
X398447D01*
G01X400814D02*
X402234Y735500D01*
G01X407915D02*
X407347Y735626D01*
X406779Y736131D01*
X406400Y737015D01*
X406211Y738025D01*
X406400Y739035D01*
X406779Y739919D01*
X407347Y740424D01*
X407915Y740550D01*
X408484Y740424D01*
X409052Y739919D01*
X409430Y739035D01*
X409525Y738025D01*
X409430Y737015D01*
X409052Y736131D01*
X408484Y735626D01*
X407915Y735500D01*
G01X413881Y740550D02*
Y737015D01*
X414260Y736131D01*
X414828Y735626D01*
X415490Y735500D01*
X416153Y735626D01*
X416721Y736131D01*
X417100Y737015D01*
G01Y735500D02*
Y740550D01*
G01X421740Y733606D02*
X422403Y733101D01*
X423160Y732975D01*
X423823Y733101D01*
X424391Y733732D01*
X424770Y734616D01*
Y740550D01*
G01Y739540D02*
X424391Y740045D01*
X423823Y740424D01*
X423160Y740550D01*
X422403Y740297D01*
X421929Y739793D01*
X421550Y738909D01*
X421361Y738025D01*
X421456Y737267D01*
X421835Y736384D01*
X422403Y735752D01*
X423160Y735500D01*
X423728Y735626D01*
X424391Y736131D01*
X424770Y736636D01*
G01X429031Y735500D02*
Y743075D01*
G01Y739414D02*
X429504Y740045D01*
X429978Y740424D01*
X430735Y740550D01*
X431303Y740424D01*
X431966Y739919D01*
X432250Y739161D01*
Y735500D01*
G01X436606D02*
Y740550D01*
G01Y739287D02*
X436985Y739919D01*
X437553Y740424D01*
X438310Y740550D01*
X438973Y740424D01*
X439541Y739919D01*
X439825Y739035D01*
Y735500D01*
G01X444370Y738909D02*
X447400D01*
X447116Y739793D01*
X446643Y740297D01*
X445980Y740550D01*
X445317Y740424D01*
X444749Y740045D01*
X444370Y739161D01*
X444181Y738404D01*
Y737646D01*
X444370Y736889D01*
X444844Y736131D01*
X445412Y735626D01*
X446075Y735500D01*
X446737Y735752D01*
X447400Y736510D01*
G01X451945Y736384D02*
X452419Y735879D01*
X453081Y735500D01*
X453650D01*
X454218Y735752D01*
X454596Y736131D01*
X454786Y736636D01*
X454691Y737394D01*
X454312Y737772D01*
X452608Y738530D01*
X452229Y739414D01*
X452419Y740045D01*
X452797Y740424D01*
X453365Y740550D01*
X453934Y740424D01*
X454502Y740045D01*
G01X459520Y736384D02*
X459994Y735879D01*
X460656Y735500D01*
X461225D01*
X461793Y735752D01*
X462171Y736131D01*
X462361Y736636D01*
X462266Y737394D01*
X461887Y737772D01*
X460183Y738530D01*
X459804Y739414D01*
X459994Y740045D01*
X460372Y740424D01*
X460940Y740550D01*
X461509Y740424D01*
X462077Y740045D01*
G01X394852Y827500D02*
Y835075D01*
G01X398829D02*
Y827500D01*
G01Y831287D02*
X394852D01*
G01X404415Y827500D02*
X403847Y827626D01*
X403279Y828131D01*
X402900Y829015D01*
X402711Y830025D01*
X402900Y831035D01*
X403279Y831919D01*
X403847Y832424D01*
X404415Y832550D01*
X404984Y832424D01*
X405552Y831919D01*
X405930Y831035D01*
X406025Y830025D01*
X405930Y829015D01*
X405552Y828131D01*
X404984Y827626D01*
X404415Y827500D01*
G01X411990D02*
Y835075D01*
G01X418145Y830909D02*
X421175D01*
X420891Y831793D01*
X420418Y832297D01*
X419755Y832550D01*
X419092Y832424D01*
X418524Y832045D01*
X418145Y831161D01*
X417956Y830404D01*
Y829646D01*
X418145Y828889D01*
X418619Y828131D01*
X419187Y827626D01*
X419850Y827500D01*
X420512Y827752D01*
X421175Y828510D01*
G01X437852D02*
X438610Y827879D01*
X439462Y827500D01*
X440219D01*
X440977Y827879D01*
X441545Y828510D01*
X441829Y829394D01*
X441640Y830277D01*
X441166Y831035D01*
X440314Y831540D01*
X439178Y831793D01*
X438515Y832297D01*
X438231Y833181D01*
X438420Y834065D01*
X438894Y834696D01*
X439556Y835075D01*
X440219D01*
X440882Y834823D01*
X441450Y834191D01*
G01X447415Y832550D02*
Y827500D01*
G01Y834570D02*
X447226Y834696D01*
Y834949D01*
X447415Y835075D01*
X447605Y834949D01*
Y834696D01*
X447415Y834570D01*
G01X453570Y832550D02*
X456411D01*
X453570Y827500D01*
X456411D01*
G01X461145Y830909D02*
X464175D01*
X463891Y831793D01*
X463418Y832297D01*
X462755Y832550D01*
X462092Y832424D01*
X461524Y832045D01*
X461145Y831161D01*
X460956Y830404D01*
Y829646D01*
X461145Y828889D01*
X461619Y828131D01*
X462187Y827626D01*
X462850Y827500D01*
X463512Y827752D01*
X464175Y828510D01*
G01X417473Y884500D02*
X419840Y892075D01*
X422208Y884500D01*
G01X421355Y887151D02*
X418325D01*
G01X427415Y884500D02*
Y892075D01*
G01X434990Y889550D02*
Y884500D01*
G01Y891570D02*
X434801Y891696D01*
Y891949D01*
X434990Y892075D01*
X435180Y891949D01*
Y891696D01*
X434990Y891570D01*
G01X441240Y882606D02*
X441903Y882101D01*
X442660Y881975D01*
X443323Y882101D01*
X443891Y882732D01*
X444270Y883616D01*
Y889550D01*
G01Y888540D02*
X443891Y889045D01*
X443323Y889424D01*
X442660Y889550D01*
X441903Y889297D01*
X441429Y888793D01*
X441050Y887909D01*
X440861Y887025D01*
X440956Y886267D01*
X441335Y885384D01*
X441903Y884752D01*
X442660Y884500D01*
X443228Y884626D01*
X443891Y885131D01*
X444270Y885636D01*
G01X448531Y884500D02*
Y889550D01*
G01Y888287D02*
X448910Y888919D01*
X449478Y889424D01*
X450235Y889550D01*
X450898Y889424D01*
X451466Y888919D01*
X451750Y888035D01*
Y884500D01*
G01X454875D02*
Y889550D01*
G01Y888161D02*
X455159Y888793D01*
X455632Y889297D01*
X456295Y889550D01*
X456958Y889297D01*
X457431Y888793D01*
X457715Y888161D01*
Y884500D01*
G01Y888161D02*
X458000Y888793D01*
X458473Y889297D01*
X459136Y889550D01*
X459799Y889297D01*
X460272Y888793D01*
X460556Y888035D01*
Y884500D01*
G01X463870Y887909D02*
X466900D01*
X466616Y888793D01*
X466143Y889297D01*
X465480Y889550D01*
X464817Y889424D01*
X464249Y889045D01*
X463870Y888161D01*
X463681Y887404D01*
Y886646D01*
X463870Y885889D01*
X464344Y885131D01*
X464912Y884626D01*
X465575Y884500D01*
X466237Y884752D01*
X466900Y885510D01*
G01X471256Y884500D02*
Y889550D01*
G01Y888287D02*
X471635Y888919D01*
X472203Y889424D01*
X472960Y889550D01*
X473623Y889424D01*
X474191Y888919D01*
X474475Y888035D01*
Y884500D01*
G01X480440Y892075D02*
Y884500D01*
G01X479115Y889550D02*
X481766D01*
G01X500352Y736000D02*
Y743575D01*
G01X504329D02*
Y736000D01*
G01Y739787D02*
X500352D01*
G01X509915Y736000D02*
X509347Y736126D01*
X508779Y736631D01*
X508400Y737515D01*
X508211Y738525D01*
X508400Y739535D01*
X508779Y740419D01*
X509347Y740924D01*
X509915Y741050D01*
X510484Y740924D01*
X511052Y740419D01*
X511430Y739535D01*
X511525Y738525D01*
X511430Y737515D01*
X511052Y736631D01*
X510484Y736126D01*
X509915Y736000D01*
G01X517490D02*
Y743575D01*
G01X523645Y739409D02*
X526675D01*
X526391Y740293D01*
X525918Y740797D01*
X525255Y741050D01*
X524592Y740924D01*
X524024Y740545D01*
X523645Y739661D01*
X523456Y738904D01*
Y738146D01*
X523645Y737389D01*
X524119Y736631D01*
X524687Y736126D01*
X525350Y736000D01*
X526012Y736252D01*
X526675Y737010D01*
G01X537375Y743575D02*
X538700Y736000D01*
X540215Y743575D01*
X541730Y736000D01*
X543056Y743575D01*
G01X549495Y736000D02*
Y741050D01*
G01Y740166D02*
X549116Y740671D01*
X548548Y740924D01*
X547885Y741050D01*
X547222Y740797D01*
X546654Y740293D01*
X546275Y739535D01*
X546086Y738525D01*
X546275Y737515D01*
X546654Y736757D01*
X547222Y736252D01*
X547885Y736000D01*
X548548Y736126D01*
X549116Y736505D01*
X549495Y737010D01*
G01X555365Y736000D02*
Y743575D01*
G01X562940Y736000D02*
Y743575D01*
G01X576197Y736000D02*
Y743575D01*
X578564D01*
X579321Y743196D01*
X579795Y742691D01*
X579984Y741681D01*
X579795Y740671D01*
X579227Y740040D01*
X578564Y739661D01*
X576197D01*
G01X578564D02*
X579984Y736000D01*
G01X585665D02*
X585097Y736126D01*
X584529Y736631D01*
X584150Y737515D01*
X583961Y738525D01*
X584150Y739535D01*
X584529Y740419D01*
X585097Y740924D01*
X585665Y741050D01*
X586234Y740924D01*
X586802Y740419D01*
X587180Y739535D01*
X587275Y738525D01*
X587180Y737515D01*
X586802Y736631D01*
X586234Y736126D01*
X585665Y736000D01*
G01X591631Y741050D02*
Y737515D01*
X592010Y736631D01*
X592578Y736126D01*
X593240Y736000D01*
X593903Y736126D01*
X594471Y736631D01*
X594850Y737515D01*
G01Y736000D02*
Y741050D01*
G01X599490Y734106D02*
X600153Y733601D01*
X600910Y733475D01*
X601573Y733601D01*
X602141Y734232D01*
X602520Y735116D01*
Y741050D01*
G01Y740040D02*
X602141Y740545D01*
X601573Y740924D01*
X600910Y741050D01*
X600153Y740797D01*
X599679Y740293D01*
X599300Y739409D01*
X599111Y738525D01*
X599206Y737767D01*
X599585Y736884D01*
X600153Y736252D01*
X600910Y736000D01*
X601478Y736126D01*
X602141Y736631D01*
X602520Y737136D01*
G01X606781Y736000D02*
Y743575D01*
G01Y739914D02*
X607254Y740545D01*
X607728Y740924D01*
X608485Y741050D01*
X609053Y740924D01*
X609716Y740419D01*
X610000Y739661D01*
Y736000D01*
G01X614356D02*
Y741050D01*
G01Y739787D02*
X614735Y740419D01*
X615303Y740924D01*
X616060Y741050D01*
X616723Y740924D01*
X617291Y740419D01*
X617575Y739535D01*
Y736000D01*
G01X622120Y739409D02*
X625150D01*
X624866Y740293D01*
X624393Y740797D01*
X623730Y741050D01*
X623067Y740924D01*
X622499Y740545D01*
X622120Y739661D01*
X621931Y738904D01*
Y738146D01*
X622120Y737389D01*
X622594Y736631D01*
X623162Y736126D01*
X623825Y736000D01*
X624487Y736252D01*
X625150Y737010D01*
G01X629695Y736884D02*
X630169Y736379D01*
X630831Y736000D01*
X631400D01*
X631968Y736252D01*
X632346Y736631D01*
X632536Y737136D01*
X632441Y737894D01*
X632062Y738272D01*
X630358Y739030D01*
X629979Y739914D01*
X630169Y740545D01*
X630547Y740924D01*
X631115Y741050D01*
X631684Y740924D01*
X632252Y740545D01*
G01X637270Y736884D02*
X637744Y736379D01*
X638406Y736000D01*
X638975D01*
X639543Y736252D01*
X639921Y736631D01*
X640111Y737136D01*
X640016Y737894D01*
X639637Y738272D01*
X637933Y739030D01*
X637554Y739914D01*
X637744Y740545D01*
X638122Y740924D01*
X638690Y741050D01*
X639259Y740924D01*
X639827Y740545D01*
G01X501340Y748000D02*
X500583Y748126D01*
X499920Y748631D01*
X499352Y749389D01*
X498973Y750272D01*
X498784Y751282D01*
Y752293D01*
X498973Y753303D01*
X499352Y754186D01*
X499920Y754944D01*
X500583Y755449D01*
X501340Y755575D01*
X502098Y755449D01*
X502761Y754944D01*
X503329Y754186D01*
X503708Y753303D01*
X503897Y752293D01*
Y751282D01*
X503708Y750272D01*
X503329Y749389D01*
X502761Y748631D01*
X502098Y748126D01*
X501340Y748000D01*
G01X508915Y755575D02*
Y748000D01*
G01X507590Y753050D02*
X510241D01*
G01X514881Y748000D02*
Y755575D01*
G01Y751914D02*
X515354Y752545D01*
X515828Y752924D01*
X516585Y753050D01*
X517153Y752924D01*
X517816Y752419D01*
X518100Y751661D01*
Y748000D01*
G01X522645Y751409D02*
X525675D01*
X525391Y752293D01*
X524918Y752797D01*
X524255Y753050D01*
X523592Y752924D01*
X523024Y752545D01*
X522645Y751661D01*
X522456Y750904D01*
Y750146D01*
X522645Y749389D01*
X523119Y748631D01*
X523687Y748126D01*
X524350Y748000D01*
X525012Y748252D01*
X525675Y749010D01*
G01X530315Y748000D02*
Y753050D01*
G01Y752040D02*
X530788Y752545D01*
X531262Y752924D01*
X531925Y753050D01*
X532398Y752924D01*
X532966Y752545D01*
G01X537795Y748884D02*
X538269Y748379D01*
X538931Y748000D01*
X539500D01*
X540068Y748252D01*
X540446Y748631D01*
X540636Y749136D01*
X540541Y749894D01*
X540162Y750272D01*
X538458Y751030D01*
X538079Y751914D01*
X538269Y752545D01*
X538647Y752924D01*
X539215Y753050D01*
X539784Y752924D01*
X540352Y752545D01*
G01X553892Y745475D02*
X552945Y746738D01*
X552472Y748000D01*
Y753050D01*
X552945Y754313D01*
X553892Y755575D01*
G01X561940Y748000D02*
Y755575D01*
G01X569515Y753050D02*
Y748000D01*
G01Y755070D02*
X569326Y755196D01*
Y755449D01*
X569515Y755575D01*
X569705Y755449D01*
Y755196D01*
X569515Y755070D01*
G01X575481Y748000D02*
Y755575D01*
G01X578511Y753050D02*
X575481Y750146D01*
G01X576712Y751282D02*
X578700Y748000D01*
G01X583245Y751409D02*
X586275D01*
X585991Y752293D01*
X585518Y752797D01*
X584855Y753050D01*
X584192Y752924D01*
X583624Y752545D01*
X583245Y751661D01*
X583056Y750904D01*
Y750146D01*
X583245Y749389D01*
X583719Y748631D01*
X584287Y748126D01*
X584950Y748000D01*
X585612Y748252D01*
X586275Y749010D01*
G01X598395Y751409D02*
X601425D01*
X601141Y752293D01*
X600668Y752797D01*
X600005Y753050D01*
X599342Y752924D01*
X598774Y752545D01*
X598395Y751661D01*
X598206Y750904D01*
Y750146D01*
X598395Y749389D01*
X598869Y748631D01*
X599437Y748126D01*
X600100Y748000D01*
X600762Y748252D01*
X601425Y749010D01*
G01X607390Y748000D02*
Y755575D01*
G01X614965Y748000D02*
Y755575D01*
G01X622540Y753050D02*
Y748000D01*
G01Y755070D02*
X622351Y755196D01*
Y755449D01*
X622540Y755575D01*
X622730Y755449D01*
Y755196D01*
X622540Y755070D01*
G01X628411Y745475D02*
Y753050D01*
G01Y751914D02*
X628885Y752545D01*
X629358Y752924D01*
X630115Y753050D01*
X630778Y752924D01*
X631441Y752293D01*
X631725Y751409D01*
X631820Y750525D01*
X631725Y749641D01*
X631441Y748757D01*
X630873Y748252D01*
X630115Y748000D01*
X629453Y748126D01*
X628790Y748505D01*
X628411Y749010D01*
G01X636270Y748884D02*
X636744Y748379D01*
X637406Y748000D01*
X637975D01*
X638543Y748252D01*
X638921Y748631D01*
X639111Y749136D01*
X639016Y749894D01*
X638637Y750272D01*
X636933Y751030D01*
X636554Y751914D01*
X636744Y752545D01*
X637122Y752924D01*
X637690Y753050D01*
X638259Y752924D01*
X638827Y752545D01*
G01X643845Y751409D02*
X646875D01*
X646591Y752293D01*
X646118Y752797D01*
X645455Y753050D01*
X644792Y752924D01*
X644224Y752545D01*
X643845Y751661D01*
X643656Y750904D01*
Y750146D01*
X643845Y749389D01*
X644319Y748631D01*
X644887Y748126D01*
X645550Y748000D01*
X646212Y748252D01*
X646875Y749010D01*
G01X662120Y748000D02*
Y753050D01*
G01Y752166D02*
X661741Y752671D01*
X661173Y752924D01*
X660510Y753050D01*
X659847Y752797D01*
X659279Y752293D01*
X658900Y751535D01*
X658711Y750525D01*
X658900Y749515D01*
X659279Y748757D01*
X659847Y748252D01*
X660510Y748000D01*
X661173Y748126D01*
X661741Y748505D01*
X662120Y749010D01*
G01X666381Y748000D02*
Y753050D01*
G01Y751787D02*
X666760Y752419D01*
X667328Y752924D01*
X668085Y753050D01*
X668748Y752924D01*
X669316Y752419D01*
X669600Y751535D01*
Y748000D01*
G01X677270Y755575D02*
Y748000D01*
G01Y749136D02*
X676891Y748505D01*
X676323Y748126D01*
X675660Y748000D01*
X674903Y748252D01*
X674335Y748884D01*
X673956Y749641D01*
X673861Y750525D01*
X673956Y751409D01*
X674335Y752166D01*
X674903Y752797D01*
X675660Y753050D01*
X676323Y752924D01*
X676796Y752671D01*
X677270Y752166D01*
G01X690715Y748000D02*
X690147Y748126D01*
X689579Y748631D01*
X689200Y749515D01*
X689011Y750525D01*
X689200Y751535D01*
X689579Y752419D01*
X690147Y752924D01*
X690715Y753050D01*
X691284Y752924D01*
X691852Y752419D01*
X692230Y751535D01*
X692325Y750525D01*
X692230Y749515D01*
X691852Y748631D01*
X691284Y748126D01*
X690715Y748000D01*
G01X698290Y755575D02*
Y748000D01*
G01X696965Y753050D02*
X699616D01*
G01X704256Y748000D02*
Y755575D01*
G01Y751914D02*
X704729Y752545D01*
X705203Y752924D01*
X705960Y753050D01*
X706528Y752924D01*
X707191Y752419D01*
X707475Y751661D01*
Y748000D01*
G01X712020Y751409D02*
X715050D01*
X714766Y752293D01*
X714293Y752797D01*
X713630Y753050D01*
X712967Y752924D01*
X712399Y752545D01*
X712020Y751661D01*
X711831Y750904D01*
Y750146D01*
X712020Y749389D01*
X712494Y748631D01*
X713062Y748126D01*
X713725Y748000D01*
X714387Y748252D01*
X715050Y749010D01*
G01X719690Y748000D02*
Y753050D01*
G01Y752040D02*
X720163Y752545D01*
X720637Y752924D01*
X721300Y753050D01*
X721773Y752924D01*
X722341Y752545D01*
G01X727170Y748884D02*
X727644Y748379D01*
X728306Y748000D01*
X728875D01*
X729443Y748252D01*
X729821Y748631D01*
X730011Y749136D01*
X729916Y749894D01*
X729537Y750272D01*
X727833Y751030D01*
X727454Y751914D01*
X727644Y752545D01*
X728022Y752924D01*
X728590Y753050D01*
X729159Y752924D01*
X729727Y752545D01*
G01X736639Y745475D02*
X737586Y746738D01*
X738059Y748000D01*
Y753050D01*
X737586Y754313D01*
X736639Y755575D01*
G01X499447Y759500D02*
Y767075D01*
X501719D01*
X502477Y766696D01*
X503045Y765813D01*
X503234Y764803D01*
X503045Y763793D01*
X502571Y763035D01*
X501719Y762656D01*
X499447D01*
G01X508915Y767075D02*
Y759500D01*
G01X506738Y767075D02*
X511093D01*
G01X514502Y759500D02*
Y767075D01*
G01X518479D02*
Y759500D01*
G01Y763287D02*
X514502D01*
G01X522361Y759248D02*
X525770Y767075D01*
G01X529463Y759500D02*
Y767075D01*
X533818Y759500D01*
Y767075D01*
G01X537322Y759500D02*
Y767075D01*
X539594D01*
X540352Y766696D01*
X540920Y765813D01*
X541109Y764803D01*
X540920Y763793D01*
X540446Y763035D01*
X539594Y762656D01*
X537322D01*
G01X546790Y767075D02*
Y759500D01*
G01X544613Y767075D02*
X548968D01*
G01X552377Y759500D02*
Y767075D01*
G01X556354D02*
Y759500D01*
G01Y763287D02*
X552377D01*
G01X567622Y759500D02*
X571409Y762025D01*
X567622Y764550D01*
G01X575860Y760889D02*
X578321D01*
G01Y763161D02*
X575860D01*
G01X582582Y760636D02*
X583150Y760005D01*
X583813Y759626D01*
X584665Y759500D01*
X585518Y759752D01*
X586180Y760257D01*
X586654Y761141D01*
X586749Y762151D01*
X586559Y763161D01*
X586086Y763793D01*
X585423Y764297D01*
X584760Y764424D01*
X584097Y764297D01*
X583245Y763793D01*
X583529Y767075D01*
X586086D01*
G01X596975Y759500D02*
Y764550D01*
G01Y763161D02*
X597259Y763793D01*
X597732Y764297D01*
X598395Y764550D01*
X599058Y764297D01*
X599531Y763793D01*
X599815Y763161D01*
Y759500D01*
G01Y763161D02*
X600100Y763793D01*
X600573Y764297D01*
X601236Y764550D01*
X601899Y764297D01*
X602372Y763793D01*
X602656Y763035D01*
Y759500D01*
G01X604550D02*
Y764550D01*
G01Y763161D02*
X604834Y763793D01*
X605307Y764297D01*
X605970Y764550D01*
X606633Y764297D01*
X607106Y763793D01*
X607390Y763161D01*
Y759500D01*
G01Y763161D02*
X607675Y763793D01*
X608148Y764297D01*
X608811Y764550D01*
X609474Y764297D01*
X609947Y763793D01*
X610231Y763035D01*
Y759500D01*
G01X499663Y784500D02*
Y792075D01*
X504018Y784500D01*
Y792075D01*
G01X507522Y784500D02*
Y792075D01*
X509794D01*
X510552Y791696D01*
X511120Y790813D01*
X511309Y789803D01*
X511120Y788793D01*
X510646Y788035D01*
X509794Y787656D01*
X507522D01*
G01X516990Y792075D02*
Y784500D01*
G01X514813Y792075D02*
X519168D01*
G01X522577Y784500D02*
Y792075D01*
G01X526554D02*
Y784500D01*
G01Y788287D02*
X522577D01*
G01X537727Y785510D02*
X538485Y784879D01*
X539337Y784500D01*
X540094D01*
X540852Y784879D01*
X541420Y785510D01*
X541704Y786394D01*
X541515Y787277D01*
X541041Y788035D01*
X540189Y788540D01*
X539053Y788793D01*
X538390Y789297D01*
X538106Y790181D01*
X538295Y791065D01*
X538769Y791696D01*
X539431Y792075D01*
X540094D01*
X540757Y791823D01*
X541325Y791191D01*
G01X547290Y789550D02*
Y784500D01*
G01Y791570D02*
X547101Y791696D01*
Y791949D01*
X547290Y792075D01*
X547480Y791949D01*
Y791696D01*
X547290Y791570D01*
G01X553445Y789550D02*
X556286D01*
X553445Y784500D01*
X556286D01*
G01X561020Y787909D02*
X564050D01*
X563766Y788793D01*
X563293Y789297D01*
X562630Y789550D01*
X561967Y789424D01*
X561399Y789045D01*
X561020Y788161D01*
X560831Y787404D01*
Y786646D01*
X561020Y785889D01*
X561494Y785131D01*
X562062Y784626D01*
X562725Y784500D01*
X563387Y784752D01*
X564050Y785510D01*
G01X575507Y786015D02*
X576075Y785131D01*
X576833Y784626D01*
X577685Y784500D01*
X578443Y784626D01*
X579200Y785257D01*
X579674Y786015D01*
X579768Y786772D01*
X579579Y787656D01*
X578916Y788287D01*
X578253Y788540D01*
X577401D01*
G01X578253D02*
X578821Y788919D01*
X579295Y789550D01*
X579484Y790307D01*
X579295Y791065D01*
X578821Y791696D01*
X577969Y792075D01*
X577117Y791949D01*
X576265Y791444D01*
G01X585165Y784248D02*
X584976Y784374D01*
Y784626D01*
X585165Y784752D01*
X585355Y784626D01*
Y784374D01*
X585165Y784248D01*
G01X590657Y785636D02*
X591225Y785005D01*
X591888Y784626D01*
X592740Y784500D01*
X593593Y784752D01*
X594255Y785257D01*
X594729Y786141D01*
X594824Y787151D01*
X594634Y788161D01*
X594161Y788793D01*
X593498Y789297D01*
X592835Y789424D01*
X592172Y789297D01*
X591320Y788793D01*
X591604Y792075D01*
X594161D01*
G01X598232Y785636D02*
X598800Y785005D01*
X599463Y784626D01*
X600315Y784500D01*
X601168Y784752D01*
X601830Y785257D01*
X602304Y786141D01*
X602399Y787151D01*
X602209Y788161D01*
X601736Y788793D01*
X601073Y789297D01*
X600410Y789424D01*
X599747Y789297D01*
X598895Y788793D01*
X599179Y792075D01*
X601736D01*
G01X605050Y784500D02*
Y789550D01*
G01Y788161D02*
X605334Y788793D01*
X605807Y789297D01*
X606470Y789550D01*
X607133Y789297D01*
X607606Y788793D01*
X607890Y788161D01*
Y784500D01*
G01Y788161D02*
X608175Y788793D01*
X608648Y789297D01*
X609311Y789550D01*
X609974Y789297D01*
X610447Y788793D01*
X610731Y788035D01*
Y784500D01*
G01X612625D02*
Y789550D01*
G01Y788161D02*
X612909Y788793D01*
X613382Y789297D01*
X614045Y789550D01*
X614708Y789297D01*
X615181Y788793D01*
X615465Y788161D01*
Y784500D01*
G01Y788161D02*
X615750Y788793D01*
X616223Y789297D01*
X616886Y789550D01*
X617549Y789297D01*
X618022Y788793D01*
X618306Y788035D01*
Y784500D01*
G01X630142Y781975D02*
X629195Y783238D01*
X628722Y784500D01*
Y789550D01*
X629195Y790813D01*
X630142Y792075D01*
G01X638190Y784500D02*
X637622Y784626D01*
X637054Y785131D01*
X636675Y786015D01*
X636486Y787025D01*
X636675Y788035D01*
X637054Y788919D01*
X637622Y789424D01*
X638190Y789550D01*
X638759Y789424D01*
X639327Y788919D01*
X639705Y788035D01*
X639800Y787025D01*
X639705Y786015D01*
X639327Y785131D01*
X638759Y784626D01*
X638190Y784500D01*
G01X644156D02*
Y789550D01*
G01Y788287D02*
X644535Y788919D01*
X645103Y789424D01*
X645860Y789550D01*
X646523Y789424D01*
X647091Y788919D01*
X647375Y788035D01*
Y784500D01*
G01X659211D02*
Y792075D01*
G01Y788287D02*
X659685Y789045D01*
X660253Y789424D01*
X660821Y789550D01*
X661673Y789297D01*
X662241Y788793D01*
X662620Y787909D01*
Y786899D01*
X662430Y785889D01*
X662052Y785131D01*
X661389Y784626D01*
X660821Y784500D01*
X660253Y784626D01*
X659685Y785005D01*
X659211Y785636D01*
G01X667165Y784500D02*
Y789550D01*
G01Y788540D02*
X667638Y789045D01*
X668112Y789424D01*
X668775Y789550D01*
X669248Y789424D01*
X669816Y789045D01*
G01X674645Y787909D02*
X677675D01*
X677391Y788793D01*
X676918Y789297D01*
X676255Y789550D01*
X675592Y789424D01*
X675024Y789045D01*
X674645Y788161D01*
X674456Y787404D01*
Y786646D01*
X674645Y785889D01*
X675119Y785131D01*
X675687Y784626D01*
X676350Y784500D01*
X677012Y784752D01*
X677675Y785510D01*
G01X685345Y784500D02*
Y789550D01*
G01Y788666D02*
X684966Y789171D01*
X684398Y789424D01*
X683735Y789550D01*
X683072Y789297D01*
X682504Y788793D01*
X682125Y788035D01*
X681936Y787025D01*
X682125Y786015D01*
X682504Y785257D01*
X683072Y784752D01*
X683735Y784500D01*
X684398Y784626D01*
X684966Y785005D01*
X685345Y785510D01*
G01X689606Y784500D02*
Y792075D01*
G01X692636Y789550D02*
X689606Y786646D01*
G01X690837Y787782D02*
X692825Y784500D01*
G01X700495D02*
Y789550D01*
G01Y788666D02*
X700116Y789171D01*
X699548Y789424D01*
X698885Y789550D01*
X698222Y789297D01*
X697654Y788793D01*
X697275Y788035D01*
X697086Y787025D01*
X697275Y786015D01*
X697654Y785257D01*
X698222Y784752D01*
X698885Y784500D01*
X699548Y784626D01*
X700116Y785005D01*
X700495Y785510D01*
G01X703998Y789550D02*
X705135Y784500D01*
X706365Y789550D01*
X707596Y784500D01*
X708733Y789550D01*
G01X715645Y784500D02*
Y789550D01*
G01Y788666D02*
X715266Y789171D01*
X714698Y789424D01*
X714035Y789550D01*
X713372Y789297D01*
X712804Y788793D01*
X712425Y788035D01*
X712236Y787025D01*
X712425Y786015D01*
X712804Y785257D01*
X713372Y784752D01*
X714035Y784500D01*
X714698Y784626D01*
X715266Y785005D01*
X715645Y785510D01*
G01X719527Y782228D02*
X720095Y781975D01*
X720853Y782228D01*
X721326Y782732D01*
X721705Y783364D01*
X722273Y785384D01*
X723504Y789550D01*
G01X720474D02*
X722273Y785384D01*
G01X729564Y781975D02*
X730511Y783238D01*
X730984Y784500D01*
Y789550D01*
X730511Y790813D01*
X729564Y792075D01*
G01X499663Y772500D02*
Y780075D01*
X504018Y772500D01*
Y780075D01*
G01X507522Y772500D02*
Y780075D01*
X509794D01*
X510552Y779696D01*
X511120Y778813D01*
X511309Y777803D01*
X511120Y776793D01*
X510646Y776035D01*
X509794Y775656D01*
X507522D01*
G01X516990Y780075D02*
Y772500D01*
G01X514813Y780075D02*
X519168D01*
G01X522577Y772500D02*
Y780075D01*
G01X526554D02*
Y772500D01*
G01Y776287D02*
X522577D01*
G01X537727Y773510D02*
X538485Y772879D01*
X539337Y772500D01*
X540094D01*
X540852Y772879D01*
X541420Y773510D01*
X541704Y774394D01*
X541515Y775277D01*
X541041Y776035D01*
X540189Y776540D01*
X539053Y776793D01*
X538390Y777297D01*
X538106Y778181D01*
X538295Y779065D01*
X538769Y779696D01*
X539431Y780075D01*
X540094D01*
X540757Y779823D01*
X541325Y779191D01*
G01X547290Y777550D02*
Y772500D01*
G01Y779570D02*
X547101Y779696D01*
Y779949D01*
X547290Y780075D01*
X547480Y779949D01*
Y779696D01*
X547290Y779570D01*
G01X553445Y777550D02*
X556286D01*
X553445Y772500D01*
X556286D01*
G01X561020Y775909D02*
X564050D01*
X563766Y776793D01*
X563293Y777297D01*
X562630Y777550D01*
X561967Y777424D01*
X561399Y777045D01*
X561020Y776161D01*
X560831Y775404D01*
Y774646D01*
X561020Y773889D01*
X561494Y773131D01*
X562062Y772626D01*
X562725Y772500D01*
X563387Y772752D01*
X564050Y773510D01*
G01X575791Y778813D02*
X576360Y779570D01*
X577022Y779949D01*
X577780Y780075D01*
X578727Y779823D01*
X579390Y779191D01*
X579579Y778434D01*
X579484Y777676D01*
X579105Y777045D01*
X577212Y775782D01*
X576360Y774899D01*
X575791Y773636D01*
X575602Y772500D01*
X579579D01*
G01X585165Y772248D02*
X584976Y772374D01*
Y772626D01*
X585165Y772752D01*
X585355Y772626D01*
Y772374D01*
X585165Y772248D01*
G01X592740Y772500D02*
Y780075D01*
X591604Y778560D01*
G01Y772500D02*
X593877D01*
G01X600315D02*
X600978Y772626D01*
X601736Y773005D01*
X602209Y773636D01*
X602399Y774520D01*
X602209Y775404D01*
X601641Y776161D01*
X600789Y776540D01*
X599842D01*
X599274Y776793D01*
X598800Y777424D01*
X598611Y778307D01*
X598895Y779191D01*
X599558Y779823D01*
X600315Y780075D01*
X601073Y779823D01*
X601736Y779191D01*
X602020Y778307D01*
X601830Y777424D01*
X601357Y776793D01*
X600789Y776540D01*
X599842D01*
X598990Y776161D01*
X598422Y775404D01*
X598232Y774520D01*
X598422Y773636D01*
X598895Y773005D01*
X599653Y772626D01*
X600315Y772500D01*
G01X605050D02*
Y777550D01*
G01Y776161D02*
X605334Y776793D01*
X605807Y777297D01*
X606470Y777550D01*
X607133Y777297D01*
X607606Y776793D01*
X607890Y776161D01*
Y772500D01*
G01Y776161D02*
X608175Y776793D01*
X608648Y777297D01*
X609311Y777550D01*
X609974Y777297D01*
X610447Y776793D01*
X610731Y776035D01*
Y772500D01*
G01X612625D02*
Y777550D01*
G01Y776161D02*
X612909Y776793D01*
X613382Y777297D01*
X614045Y777550D01*
X614708Y777297D01*
X615181Y776793D01*
X615465Y776161D01*
Y772500D01*
G01Y776161D02*
X615750Y776793D01*
X616223Y777297D01*
X616886Y777550D01*
X617549Y777297D01*
X618022Y776793D01*
X618306Y776035D01*
Y772500D01*
G01X630142Y769975D02*
X629195Y771238D01*
X628722Y772500D01*
Y777550D01*
X629195Y778813D01*
X630142Y780075D01*
G01X638190Y772500D02*
X637622Y772626D01*
X637054Y773131D01*
X636675Y774015D01*
X636486Y775025D01*
X636675Y776035D01*
X637054Y776919D01*
X637622Y777424D01*
X638190Y777550D01*
X638759Y777424D01*
X639327Y776919D01*
X639705Y776035D01*
X639800Y775025D01*
X639705Y774015D01*
X639327Y773131D01*
X638759Y772626D01*
X638190Y772500D01*
G01X644156D02*
Y777550D01*
G01Y776287D02*
X644535Y776919D01*
X645103Y777424D01*
X645860Y777550D01*
X646523Y777424D01*
X647091Y776919D01*
X647375Y776035D01*
Y772500D01*
G01X659211D02*
Y780075D01*
G01Y776287D02*
X659685Y777045D01*
X660253Y777424D01*
X660821Y777550D01*
X661673Y777297D01*
X662241Y776793D01*
X662620Y775909D01*
Y774899D01*
X662430Y773889D01*
X662052Y773131D01*
X661389Y772626D01*
X660821Y772500D01*
X660253Y772626D01*
X659685Y773005D01*
X659211Y773636D01*
G01X667165Y772500D02*
Y777550D01*
G01Y776540D02*
X667638Y777045D01*
X668112Y777424D01*
X668775Y777550D01*
X669248Y777424D01*
X669816Y777045D01*
G01X674645Y775909D02*
X677675D01*
X677391Y776793D01*
X676918Y777297D01*
X676255Y777550D01*
X675592Y777424D01*
X675024Y777045D01*
X674645Y776161D01*
X674456Y775404D01*
Y774646D01*
X674645Y773889D01*
X675119Y773131D01*
X675687Y772626D01*
X676350Y772500D01*
X677012Y772752D01*
X677675Y773510D01*
G01X685345Y772500D02*
Y777550D01*
G01Y776666D02*
X684966Y777171D01*
X684398Y777424D01*
X683735Y777550D01*
X683072Y777297D01*
X682504Y776793D01*
X682125Y776035D01*
X681936Y775025D01*
X682125Y774015D01*
X682504Y773257D01*
X683072Y772752D01*
X683735Y772500D01*
X684398Y772626D01*
X684966Y773005D01*
X685345Y773510D01*
G01X689606Y772500D02*
Y780075D01*
G01X692636Y777550D02*
X689606Y774646D01*
G01X690837Y775782D02*
X692825Y772500D01*
G01X700495D02*
Y777550D01*
G01Y776666D02*
X700116Y777171D01*
X699548Y777424D01*
X698885Y777550D01*
X698222Y777297D01*
X697654Y776793D01*
X697275Y776035D01*
X697086Y775025D01*
X697275Y774015D01*
X697654Y773257D01*
X698222Y772752D01*
X698885Y772500D01*
X699548Y772626D01*
X700116Y773005D01*
X700495Y773510D01*
G01X703998Y777550D02*
X705135Y772500D01*
X706365Y777550D01*
X707596Y772500D01*
X708733Y777550D01*
G01X715645Y772500D02*
Y777550D01*
G01Y776666D02*
X715266Y777171D01*
X714698Y777424D01*
X714035Y777550D01*
X713372Y777297D01*
X712804Y776793D01*
X712425Y776035D01*
X712236Y775025D01*
X712425Y774015D01*
X712804Y773257D01*
X713372Y772752D01*
X714035Y772500D01*
X714698Y772626D01*
X715266Y773005D01*
X715645Y773510D01*
G01X719527Y770228D02*
X720095Y769975D01*
X720853Y770228D01*
X721326Y770732D01*
X721705Y771364D01*
X722273Y773384D01*
X723504Y777550D01*
G01X720474D02*
X722273Y773384D01*
G01X729564Y769975D02*
X730511Y771238D01*
X730984Y772500D01*
Y777550D01*
X730511Y778813D01*
X729564Y780075D01*
G01X499663Y798000D02*
Y805575D01*
X504018Y798000D01*
Y805575D01*
G01X507522Y798000D02*
Y805575D01*
X509794D01*
X510552Y805196D01*
X511120Y804313D01*
X511309Y803303D01*
X511120Y802293D01*
X510646Y801535D01*
X509794Y801156D01*
X507522D01*
G01X516990Y805575D02*
Y798000D01*
G01X514813Y805575D02*
X519168D01*
G01X522577Y798000D02*
Y805575D01*
G01X526554D02*
Y798000D01*
G01Y801787D02*
X522577D01*
G01X537727Y799010D02*
X538485Y798379D01*
X539337Y798000D01*
X540094D01*
X540852Y798379D01*
X541420Y799010D01*
X541704Y799894D01*
X541515Y800777D01*
X541041Y801535D01*
X540189Y802040D01*
X539053Y802293D01*
X538390Y802797D01*
X538106Y803681D01*
X538295Y804565D01*
X538769Y805196D01*
X539431Y805575D01*
X540094D01*
X540757Y805323D01*
X541325Y804691D01*
G01X547290Y803050D02*
Y798000D01*
G01Y805070D02*
X547101Y805196D01*
Y805449D01*
X547290Y805575D01*
X547480Y805449D01*
Y805196D01*
X547290Y805070D01*
G01X553445Y803050D02*
X556286D01*
X553445Y798000D01*
X556286D01*
G01X561020Y801409D02*
X564050D01*
X563766Y802293D01*
X563293Y802797D01*
X562630Y803050D01*
X561967Y802924D01*
X561399Y802545D01*
X561020Y801661D01*
X560831Y800904D01*
Y800146D01*
X561020Y799389D01*
X561494Y798631D01*
X562062Y798126D01*
X562725Y798000D01*
X563387Y798252D01*
X564050Y799010D01*
G01X571909Y798000D02*
X568122Y800525D01*
X571909Y803050D01*
G01X583082Y799136D02*
X583650Y798505D01*
X584313Y798126D01*
X585165Y798000D01*
X586018Y798252D01*
X586680Y798757D01*
X587154Y799641D01*
X587249Y800651D01*
X587059Y801661D01*
X586586Y802293D01*
X585923Y802797D01*
X585260Y802924D01*
X584597Y802797D01*
X583745Y802293D01*
X584029Y805575D01*
X586586D01*
G01X589900Y798000D02*
Y803050D01*
G01Y801661D02*
X590184Y802293D01*
X590657Y802797D01*
X591320Y803050D01*
X591983Y802797D01*
X592456Y802293D01*
X592740Y801661D01*
Y798000D01*
G01Y801661D02*
X593025Y802293D01*
X593498Y802797D01*
X594161Y803050D01*
X594824Y802797D01*
X595297Y802293D01*
X595581Y801535D01*
Y798000D01*
G01X597475D02*
Y803050D01*
G01Y801661D02*
X597759Y802293D01*
X598232Y802797D01*
X598895Y803050D01*
X599558Y802797D01*
X600031Y802293D01*
X600315Y801661D01*
Y798000D01*
G01Y801661D02*
X600600Y802293D01*
X601073Y802797D01*
X601736Y803050D01*
X602399Y802797D01*
X602872Y802293D01*
X603156Y801535D01*
Y798000D01*
G01X614992Y795475D02*
X614045Y796738D01*
X613572Y798000D01*
Y803050D01*
X614045Y804313D01*
X614992Y805575D01*
G01X621431Y798000D02*
Y803050D01*
G01Y801787D02*
X621810Y802419D01*
X622378Y802924D01*
X623135Y803050D01*
X623798Y802924D01*
X624366Y802419D01*
X624650Y801535D01*
Y798000D01*
G01X630615D02*
X630047Y798126D01*
X629479Y798631D01*
X629100Y799515D01*
X628911Y800525D01*
X629100Y801535D01*
X629479Y802419D01*
X630047Y802924D01*
X630615Y803050D01*
X631184Y802924D01*
X631752Y802419D01*
X632130Y801535D01*
X632225Y800525D01*
X632130Y799515D01*
X631752Y798631D01*
X631184Y798126D01*
X630615Y798000D01*
G01X638190Y805575D02*
Y798000D01*
G01X636865Y803050D02*
X639516D01*
G01X653340Y798000D02*
X652772Y798126D01*
X652204Y798631D01*
X651825Y799515D01*
X651636Y800525D01*
X651825Y801535D01*
X652204Y802419D01*
X652772Y802924D01*
X653340Y803050D01*
X653909Y802924D01*
X654477Y802419D01*
X654855Y801535D01*
X654950Y800525D01*
X654855Y799515D01*
X654477Y798631D01*
X653909Y798126D01*
X653340Y798000D01*
G01X659306D02*
Y803050D01*
G01Y801787D02*
X659685Y802419D01*
X660253Y802924D01*
X661010Y803050D01*
X661673Y802924D01*
X662241Y802419D01*
X662525Y801535D01*
Y798000D01*
G01X674361D02*
Y805575D01*
G01Y801787D02*
X674835Y802545D01*
X675403Y802924D01*
X675971Y803050D01*
X676823Y802797D01*
X677391Y802293D01*
X677770Y801409D01*
Y800399D01*
X677580Y799389D01*
X677202Y798631D01*
X676539Y798126D01*
X675971Y798000D01*
X675403Y798126D01*
X674835Y798505D01*
X674361Y799136D01*
G01X682315Y798000D02*
Y803050D01*
G01Y802040D02*
X682788Y802545D01*
X683262Y802924D01*
X683925Y803050D01*
X684398Y802924D01*
X684966Y802545D01*
G01X689795Y801409D02*
X692825D01*
X692541Y802293D01*
X692068Y802797D01*
X691405Y803050D01*
X690742Y802924D01*
X690174Y802545D01*
X689795Y801661D01*
X689606Y800904D01*
Y800146D01*
X689795Y799389D01*
X690269Y798631D01*
X690837Y798126D01*
X691500Y798000D01*
X692162Y798252D01*
X692825Y799010D01*
G01X700495Y798000D02*
Y803050D01*
G01Y802166D02*
X700116Y802671D01*
X699548Y802924D01*
X698885Y803050D01*
X698222Y802797D01*
X697654Y802293D01*
X697275Y801535D01*
X697086Y800525D01*
X697275Y799515D01*
X697654Y798757D01*
X698222Y798252D01*
X698885Y798000D01*
X699548Y798126D01*
X700116Y798505D01*
X700495Y799010D01*
G01X704756Y798000D02*
Y805575D01*
G01X707786Y803050D02*
X704756Y800146D01*
G01X705987Y801282D02*
X707975Y798000D01*
G01X715645D02*
Y803050D01*
G01Y802166D02*
X715266Y802671D01*
X714698Y802924D01*
X714035Y803050D01*
X713372Y802797D01*
X712804Y802293D01*
X712425Y801535D01*
X712236Y800525D01*
X712425Y799515D01*
X712804Y798757D01*
X713372Y798252D01*
X714035Y798000D01*
X714698Y798126D01*
X715266Y798505D01*
X715645Y799010D01*
G01X719148Y803050D02*
X720285Y798000D01*
X721515Y803050D01*
X722746Y798000D01*
X723883Y803050D01*
G01X730795Y798000D02*
Y803050D01*
G01Y802166D02*
X730416Y802671D01*
X729848Y802924D01*
X729185Y803050D01*
X728522Y802797D01*
X727954Y802293D01*
X727575Y801535D01*
X727386Y800525D01*
X727575Y799515D01*
X727954Y798757D01*
X728522Y798252D01*
X729185Y798000D01*
X729848Y798126D01*
X730416Y798505D01*
X730795Y799010D01*
G01X734677Y795728D02*
X735245Y795475D01*
X736003Y795728D01*
X736476Y796232D01*
X736855Y796864D01*
X737423Y798884D01*
X738654Y803050D01*
G01X735624D02*
X737423Y798884D01*
G01X744714Y795475D02*
X745661Y796738D01*
X746134Y798000D01*
Y803050D01*
X745661Y804313D01*
X744714Y805575D01*
G01X500367Y809475D02*
X499420Y810738D01*
X498947Y812000D01*
Y817050D01*
X499420Y818313D01*
X500367Y819575D01*
G01X506427Y813010D02*
X507185Y812379D01*
X508037Y812000D01*
X508794D01*
X509552Y812379D01*
X510120Y813010D01*
X510404Y813894D01*
X510215Y814777D01*
X509741Y815535D01*
X508889Y816040D01*
X507753Y816293D01*
X507090Y816797D01*
X506806Y817681D01*
X506995Y818565D01*
X507469Y819196D01*
X508131Y819575D01*
X508794D01*
X509457Y819323D01*
X510025Y818691D01*
G01X514381Y817050D02*
Y813515D01*
X514760Y812631D01*
X515328Y812126D01*
X515990Y812000D01*
X516653Y812126D01*
X517221Y812631D01*
X517600Y813515D01*
G01Y812000D02*
Y817050D01*
G01X522240Y812000D02*
Y817050D01*
G01Y816040D02*
X522713Y816545D01*
X523187Y816924D01*
X523850Y817050D01*
X524323Y816924D01*
X524891Y816545D01*
G01X530572Y812000D02*
Y818439D01*
X530762Y819070D01*
X531140Y819449D01*
X531709Y819575D01*
X532277Y819323D01*
X532561Y818691D01*
G01X531425Y816545D02*
X529531D01*
G01X540420Y812000D02*
Y817050D01*
G01Y816166D02*
X540041Y816671D01*
X539473Y816924D01*
X538810Y817050D01*
X538147Y816797D01*
X537579Y816293D01*
X537200Y815535D01*
X537011Y814525D01*
X537200Y813515D01*
X537579Y812757D01*
X538147Y812252D01*
X538810Y812000D01*
X539473Y812126D01*
X540041Y812505D01*
X540420Y813010D01*
G01X547805Y816419D02*
X547143Y816924D01*
X546575Y817050D01*
X545817Y816797D01*
X545249Y816293D01*
X544870Y815409D01*
X544775Y814525D01*
X544870Y813641D01*
X545249Y812884D01*
X545817Y812252D01*
X546575Y812000D01*
X547237Y812252D01*
X547805Y812757D01*
G01X552445Y815409D02*
X555475D01*
X555191Y816293D01*
X554718Y816797D01*
X554055Y817050D01*
X553392Y816924D01*
X552824Y816545D01*
X552445Y815661D01*
X552256Y814904D01*
Y814146D01*
X552445Y813389D01*
X552919Y812631D01*
X553487Y812126D01*
X554150Y812000D01*
X554812Y812252D01*
X555475Y813010D01*
G01X569015Y819575D02*
Y812000D01*
G01X567690Y817050D02*
X570341D01*
G01X575265Y812000D02*
Y817050D01*
G01Y816040D02*
X575738Y816545D01*
X576212Y816924D01*
X576875Y817050D01*
X577348Y816924D01*
X577916Y816545D01*
G01X582745Y815409D02*
X585775D01*
X585491Y816293D01*
X585018Y816797D01*
X584355Y817050D01*
X583692Y816924D01*
X583124Y816545D01*
X582745Y815661D01*
X582556Y814904D01*
Y814146D01*
X582745Y813389D01*
X583219Y812631D01*
X583787Y812126D01*
X584450Y812000D01*
X585112Y812252D01*
X585775Y813010D01*
G01X593445Y812000D02*
Y817050D01*
G01Y816166D02*
X593066Y816671D01*
X592498Y816924D01*
X591835Y817050D01*
X591172Y816797D01*
X590604Y816293D01*
X590225Y815535D01*
X590036Y814525D01*
X590225Y813515D01*
X590604Y812757D01*
X591172Y812252D01*
X591835Y812000D01*
X592498Y812126D01*
X593066Y812505D01*
X593445Y813010D01*
G01X599315Y819575D02*
Y812000D01*
G01X597990Y817050D02*
X600641D01*
G01X604050Y812000D02*
Y817050D01*
G01Y815661D02*
X604334Y816293D01*
X604807Y816797D01*
X605470Y817050D01*
X606133Y816797D01*
X606606Y816293D01*
X606890Y815661D01*
Y812000D01*
G01Y815661D02*
X607175Y816293D01*
X607648Y816797D01*
X608311Y817050D01*
X608974Y816797D01*
X609447Y816293D01*
X609731Y815535D01*
Y812000D01*
G01X613045Y815409D02*
X616075D01*
X615791Y816293D01*
X615318Y816797D01*
X614655Y817050D01*
X613992Y816924D01*
X613424Y816545D01*
X613045Y815661D01*
X612856Y814904D01*
Y814146D01*
X613045Y813389D01*
X613519Y812631D01*
X614087Y812126D01*
X614750Y812000D01*
X615412Y812252D01*
X616075Y813010D01*
G01X620431Y812000D02*
Y817050D01*
G01Y815787D02*
X620810Y816419D01*
X621378Y816924D01*
X622135Y817050D01*
X622798Y816924D01*
X623366Y816419D01*
X623650Y815535D01*
Y812000D01*
G01X629615Y819575D02*
Y812000D01*
G01X628290Y817050D02*
X630941D01*
G01X644765D02*
Y812000D01*
G01Y819070D02*
X644576Y819196D01*
Y819449D01*
X644765Y819575D01*
X644955Y819449D01*
Y819196D01*
X644765Y819070D01*
G01X650920Y812884D02*
X651394Y812379D01*
X652056Y812000D01*
X652625D01*
X653193Y812252D01*
X653571Y812631D01*
X653761Y813136D01*
X653666Y813894D01*
X653287Y814272D01*
X651583Y815030D01*
X651204Y815914D01*
X651394Y816545D01*
X651772Y816924D01*
X652340Y817050D01*
X652909Y816924D01*
X653477Y816545D01*
G01X665502Y812000D02*
Y819575D01*
G01X669479D02*
Y812000D01*
G01Y815787D02*
X665502D01*
G01X672698Y812000D02*
X675065Y819575D01*
X677433Y812000D01*
G01X676580Y814651D02*
X673550D01*
G01X680652Y813010D02*
X681410Y812379D01*
X682262Y812000D01*
X683019D01*
X683777Y812379D01*
X684345Y813010D01*
X684629Y813894D01*
X684440Y814777D01*
X683966Y815535D01*
X683114Y816040D01*
X681978Y816293D01*
X681315Y816797D01*
X681031Y817681D01*
X681220Y818565D01*
X681694Y819196D01*
X682356Y819575D01*
X683019D01*
X683682Y819323D01*
X684250Y818691D01*
G01X688322Y819575D02*
Y812000D01*
X692109D01*
G01X705365D02*
X704797Y812126D01*
X704229Y812631D01*
X703850Y813515D01*
X703661Y814525D01*
X703850Y815535D01*
X704229Y816419D01*
X704797Y816924D01*
X705365Y817050D01*
X705934Y816924D01*
X706502Y816419D01*
X706880Y815535D01*
X706975Y814525D01*
X706880Y813515D01*
X706502Y812631D01*
X705934Y812126D01*
X705365Y812000D01*
G01X711615D02*
Y817050D01*
G01Y816040D02*
X712088Y816545D01*
X712562Y816924D01*
X713225Y817050D01*
X713698Y816924D01*
X714266Y816545D01*
G01X726197Y819575D02*
Y812000D01*
X729984D01*
G01X734245Y815409D02*
X737275D01*
X736991Y816293D01*
X736518Y816797D01*
X735855Y817050D01*
X735192Y816924D01*
X734624Y816545D01*
X734245Y815661D01*
X734056Y814904D01*
Y814146D01*
X734245Y813389D01*
X734719Y812631D01*
X735287Y812126D01*
X735950Y812000D01*
X736612Y812252D01*
X737275Y813010D01*
G01X744945Y812000D02*
Y817050D01*
G01Y816166D02*
X744566Y816671D01*
X743998Y816924D01*
X743335Y817050D01*
X742672Y816797D01*
X742104Y816293D01*
X741725Y815535D01*
X741536Y814525D01*
X741725Y813515D01*
X742104Y812757D01*
X742672Y812252D01*
X743335Y812000D01*
X743998Y812126D01*
X744566Y812505D01*
X744945Y813010D01*
G01X752520Y819575D02*
Y812000D01*
G01Y813136D02*
X752141Y812505D01*
X751573Y812126D01*
X750910Y812000D01*
X750153Y812252D01*
X749585Y812884D01*
X749206Y813641D01*
X749111Y814525D01*
X749206Y815409D01*
X749585Y816166D01*
X750153Y816797D01*
X750910Y817050D01*
X751573Y816924D01*
X752046Y816671D01*
X752520Y816166D01*
G01X764166Y812000D02*
Y819575D01*
X767765D01*
G01X766439Y815914D02*
X764166D01*
G01X772215Y812000D02*
Y817050D01*
G01Y816040D02*
X772688Y816545D01*
X773162Y816924D01*
X773825Y817050D01*
X774298Y816924D01*
X774866Y816545D01*
G01X779695Y815409D02*
X782725D01*
X782441Y816293D01*
X781968Y816797D01*
X781305Y817050D01*
X780642Y816924D01*
X780074Y816545D01*
X779695Y815661D01*
X779506Y814904D01*
Y814146D01*
X779695Y813389D01*
X780169Y812631D01*
X780737Y812126D01*
X781400Y812000D01*
X782062Y812252D01*
X782725Y813010D01*
G01X787270Y815409D02*
X790300D01*
X790016Y816293D01*
X789543Y816797D01*
X788880Y817050D01*
X788217Y816924D01*
X787649Y816545D01*
X787270Y815661D01*
X787081Y814904D01*
Y814146D01*
X787270Y813389D01*
X787744Y812631D01*
X788312Y812126D01*
X788975Y812000D01*
X789637Y812252D01*
X790300Y813010D01*
G01X801852Y812000D02*
Y819575D01*
G01X805829D02*
Y812000D01*
G01Y815787D02*
X801852D01*
G01X809048Y812000D02*
X811415Y819575D01*
X813783Y812000D01*
G01X812930Y814651D02*
X809900D01*
G01X817002Y813010D02*
X817760Y812379D01*
X818612Y812000D01*
X819369D01*
X820127Y812379D01*
X820695Y813010D01*
X820979Y813894D01*
X820790Y814777D01*
X820316Y815535D01*
X819464Y816040D01*
X818328Y816293D01*
X817665Y816797D01*
X817381Y817681D01*
X817570Y818565D01*
X818044Y819196D01*
X818706Y819575D01*
X819369D01*
X820032Y819323D01*
X820600Y818691D01*
G01X824672Y819575D02*
Y812000D01*
X828459D01*
G01X834614Y809475D02*
X835561Y810738D01*
X836034Y812000D01*
Y817050D01*
X835561Y818313D01*
X834614Y819575D01*
G01X499367Y832475D02*
X498420Y833738D01*
X497947Y835000D01*
Y840050D01*
X498420Y841313D01*
X499367Y842575D01*
G01X505427Y836010D02*
X506185Y835379D01*
X507037Y835000D01*
X507794D01*
X508552Y835379D01*
X509120Y836010D01*
X509404Y836894D01*
X509215Y837777D01*
X508741Y838535D01*
X507889Y839040D01*
X506753Y839293D01*
X506090Y839797D01*
X505806Y840681D01*
X505995Y841565D01*
X506469Y842196D01*
X507131Y842575D01*
X507794D01*
X508457Y842323D01*
X509025Y841691D01*
G01X513381Y840050D02*
Y836515D01*
X513760Y835631D01*
X514328Y835126D01*
X514990Y835000D01*
X515653Y835126D01*
X516221Y835631D01*
X516600Y836515D01*
G01Y835000D02*
Y840050D01*
G01X521240Y835000D02*
Y840050D01*
G01Y839040D02*
X521713Y839545D01*
X522187Y839924D01*
X522850Y840050D01*
X523323Y839924D01*
X523891Y839545D01*
G01X529572Y835000D02*
Y841439D01*
X529762Y842070D01*
X530140Y842449D01*
X530709Y842575D01*
X531277Y842323D01*
X531561Y841691D01*
G01X530425Y839545D02*
X528531D01*
G01X539420Y835000D02*
Y840050D01*
G01Y839166D02*
X539041Y839671D01*
X538473Y839924D01*
X537810Y840050D01*
X537147Y839797D01*
X536579Y839293D01*
X536200Y838535D01*
X536011Y837525D01*
X536200Y836515D01*
X536579Y835757D01*
X537147Y835252D01*
X537810Y835000D01*
X538473Y835126D01*
X539041Y835505D01*
X539420Y836010D01*
G01X546805Y839419D02*
X546143Y839924D01*
X545575Y840050D01*
X544817Y839797D01*
X544249Y839293D01*
X543870Y838409D01*
X543775Y837525D01*
X543870Y836641D01*
X544249Y835884D01*
X544817Y835252D01*
X545575Y835000D01*
X546237Y835252D01*
X546805Y835757D01*
G01X551445Y838409D02*
X554475D01*
X554191Y839293D01*
X553718Y839797D01*
X553055Y840050D01*
X552392Y839924D01*
X551824Y839545D01*
X551445Y838661D01*
X551256Y837904D01*
Y837146D01*
X551445Y836389D01*
X551919Y835631D01*
X552487Y835126D01*
X553150Y835000D01*
X553812Y835252D01*
X554475Y836010D01*
G01X568015Y842575D02*
Y835000D01*
G01X566690Y840050D02*
X569341D01*
G01X574265Y835000D02*
Y840050D01*
G01Y839040D02*
X574738Y839545D01*
X575212Y839924D01*
X575875Y840050D01*
X576348Y839924D01*
X576916Y839545D01*
G01X581745Y838409D02*
X584775D01*
X584491Y839293D01*
X584018Y839797D01*
X583355Y840050D01*
X582692Y839924D01*
X582124Y839545D01*
X581745Y838661D01*
X581556Y837904D01*
Y837146D01*
X581745Y836389D01*
X582219Y835631D01*
X582787Y835126D01*
X583450Y835000D01*
X584112Y835252D01*
X584775Y836010D01*
G01X592445Y835000D02*
Y840050D01*
G01Y839166D02*
X592066Y839671D01*
X591498Y839924D01*
X590835Y840050D01*
X590172Y839797D01*
X589604Y839293D01*
X589225Y838535D01*
X589036Y837525D01*
X589225Y836515D01*
X589604Y835757D01*
X590172Y835252D01*
X590835Y835000D01*
X591498Y835126D01*
X592066Y835505D01*
X592445Y836010D01*
G01X598315Y842575D02*
Y835000D01*
G01X596990Y840050D02*
X599641D01*
G01X603050Y835000D02*
Y840050D01*
G01Y838661D02*
X603334Y839293D01*
X603807Y839797D01*
X604470Y840050D01*
X605133Y839797D01*
X605606Y839293D01*
X605890Y838661D01*
Y835000D01*
G01Y838661D02*
X606175Y839293D01*
X606648Y839797D01*
X607311Y840050D01*
X607974Y839797D01*
X608447Y839293D01*
X608731Y838535D01*
Y835000D01*
G01X612045Y838409D02*
X615075D01*
X614791Y839293D01*
X614318Y839797D01*
X613655Y840050D01*
X612992Y839924D01*
X612424Y839545D01*
X612045Y838661D01*
X611856Y837904D01*
Y837146D01*
X612045Y836389D01*
X612519Y835631D01*
X613087Y835126D01*
X613750Y835000D01*
X614412Y835252D01*
X615075Y836010D01*
G01X619431Y835000D02*
Y840050D01*
G01Y838787D02*
X619810Y839419D01*
X620378Y839924D01*
X621135Y840050D01*
X621798Y839924D01*
X622366Y839419D01*
X622650Y838535D01*
Y835000D01*
G01X628615Y842575D02*
Y835000D01*
G01X627290Y840050D02*
X629941D01*
G01X643765D02*
Y835000D01*
G01Y842070D02*
X643576Y842196D01*
Y842449D01*
X643765Y842575D01*
X643955Y842449D01*
Y842196D01*
X643765Y842070D01*
G01X649920Y835884D02*
X650394Y835379D01*
X651056Y835000D01*
X651625D01*
X652193Y835252D01*
X652571Y835631D01*
X652761Y836136D01*
X652666Y836894D01*
X652287Y837272D01*
X650583Y838030D01*
X650204Y838914D01*
X650394Y839545D01*
X650772Y839924D01*
X651340Y840050D01*
X651909Y839924D01*
X652477Y839545D01*
G01X666490Y840050D02*
Y835000D01*
G01Y842070D02*
X666301Y842196D01*
Y842449D01*
X666490Y842575D01*
X666680Y842449D01*
Y842196D01*
X666490Y842070D01*
G01X671225Y835000D02*
Y840050D01*
G01Y838661D02*
X671509Y839293D01*
X671982Y839797D01*
X672645Y840050D01*
X673308Y839797D01*
X673781Y839293D01*
X674065Y838661D01*
Y835000D01*
G01Y838661D02*
X674350Y839293D01*
X674823Y839797D01*
X675486Y840050D01*
X676149Y839797D01*
X676622Y839293D01*
X676906Y838535D01*
Y835000D01*
G01X678800D02*
Y840050D01*
G01Y838661D02*
X679084Y839293D01*
X679557Y839797D01*
X680220Y840050D01*
X680883Y839797D01*
X681356Y839293D01*
X681640Y838661D01*
Y835000D01*
G01Y838661D02*
X681925Y839293D01*
X682398Y839797D01*
X683061Y840050D01*
X683724Y839797D01*
X684197Y839293D01*
X684481Y838535D01*
Y835000D01*
G01X687795Y838409D02*
X690825D01*
X690541Y839293D01*
X690068Y839797D01*
X689405Y840050D01*
X688742Y839924D01*
X688174Y839545D01*
X687795Y838661D01*
X687606Y837904D01*
Y837146D01*
X687795Y836389D01*
X688269Y835631D01*
X688837Y835126D01*
X689500Y835000D01*
X690162Y835252D01*
X690825Y836010D01*
G01X695465Y835000D02*
Y840050D01*
G01Y839040D02*
X695938Y839545D01*
X696412Y839924D01*
X697075Y840050D01*
X697548Y839924D01*
X698116Y839545D01*
G01X702945Y835884D02*
X703419Y835379D01*
X704081Y835000D01*
X704650D01*
X705218Y835252D01*
X705596Y835631D01*
X705786Y836136D01*
X705691Y836894D01*
X705312Y837272D01*
X703608Y838030D01*
X703229Y838914D01*
X703419Y839545D01*
X703797Y839924D01*
X704365Y840050D01*
X704934Y839924D01*
X705502Y839545D01*
G01X711940Y840050D02*
Y835000D01*
G01Y842070D02*
X711751Y842196D01*
Y842449D01*
X711940Y842575D01*
X712130Y842449D01*
Y842196D01*
X711940Y842070D01*
G01X719515Y835000D02*
X718947Y835126D01*
X718379Y835631D01*
X718000Y836515D01*
X717811Y837525D01*
X718000Y838535D01*
X718379Y839419D01*
X718947Y839924D01*
X719515Y840050D01*
X720084Y839924D01*
X720652Y839419D01*
X721030Y838535D01*
X721125Y837525D01*
X721030Y836515D01*
X720652Y835631D01*
X720084Y835126D01*
X719515Y835000D01*
G01X725481D02*
Y840050D01*
G01Y838787D02*
X725860Y839419D01*
X726428Y839924D01*
X727185Y840050D01*
X727848Y839924D01*
X728416Y839419D01*
X728700Y838535D01*
Y835000D01*
G01X742809Y838787D02*
X744702D01*
Y836515D01*
X744134Y835757D01*
X743471Y835252D01*
X742525Y835000D01*
X741578Y835252D01*
X740915Y835757D01*
X740347Y836515D01*
X739968Y837399D01*
X739779Y838409D01*
Y839293D01*
X739968Y840050D01*
X740347Y840934D01*
X740915Y841691D01*
X741483Y842196D01*
X742240Y842575D01*
X742903D01*
X743661Y842323D01*
X744229Y841817D01*
G01X749815Y835000D02*
X749247Y835126D01*
X748679Y835631D01*
X748300Y836515D01*
X748111Y837525D01*
X748300Y838535D01*
X748679Y839419D01*
X749247Y839924D01*
X749815Y840050D01*
X750384Y839924D01*
X750952Y839419D01*
X751330Y838535D01*
X751425Y837525D01*
X751330Y836515D01*
X750952Y835631D01*
X750384Y835126D01*
X749815Y835000D01*
G01X757390D02*
Y842575D01*
G01X766670D02*
Y835000D01*
G01Y836136D02*
X766291Y835505D01*
X765723Y835126D01*
X765060Y835000D01*
X764303Y835252D01*
X763735Y835884D01*
X763356Y836641D01*
X763261Y837525D01*
X763356Y838409D01*
X763735Y839166D01*
X764303Y839797D01*
X765060Y840050D01*
X765723Y839924D01*
X766196Y839671D01*
X766670Y839166D01*
G01X772351Y833611D02*
X772730Y835252D01*
G01X782009Y835000D02*
X778222D01*
Y842575D01*
X782009D01*
G01X780494Y838914D02*
X778222D01*
G01X786081Y835000D02*
Y840050D01*
G01Y838787D02*
X786460Y839419D01*
X787028Y839924D01*
X787785Y840050D01*
X788448Y839924D01*
X789016Y839419D01*
X789300Y838535D01*
Y835000D01*
G01X795265Y842575D02*
Y835000D01*
G01X793940Y840050D02*
X796591D01*
G01X801420Y838409D02*
X804450D01*
X804166Y839293D01*
X803693Y839797D01*
X803030Y840050D01*
X802367Y839924D01*
X801799Y839545D01*
X801420Y838661D01*
X801231Y837904D01*
Y837146D01*
X801420Y836389D01*
X801894Y835631D01*
X802462Y835126D01*
X803125Y835000D01*
X803787Y835252D01*
X804450Y836010D01*
G01X808806Y835000D02*
Y842575D01*
G01X811836Y840050D02*
X808806Y837146D01*
G01X810037Y838282D02*
X812025Y835000D01*
G01X825565D02*
X824997Y835126D01*
X824429Y835631D01*
X824050Y836515D01*
X823861Y837525D01*
X824050Y838535D01*
X824429Y839419D01*
X824997Y839924D01*
X825565Y840050D01*
X826134Y839924D01*
X826702Y839419D01*
X827080Y838535D01*
X827175Y837525D01*
X827080Y836515D01*
X826702Y835631D01*
X826134Y835126D01*
X825565Y835000D01*
G01X831815D02*
Y840050D01*
G01Y839040D02*
X832288Y839545D01*
X832762Y839924D01*
X833425Y840050D01*
X833898Y839924D01*
X834466Y839545D01*
G01X847154Y842575D02*
X849427D01*
G01X848290D02*
Y835000D01*
G01X847154D02*
X849427D01*
G01X853025D02*
Y840050D01*
G01Y838661D02*
X853309Y839293D01*
X853782Y839797D01*
X854445Y840050D01*
X855108Y839797D01*
X855581Y839293D01*
X855865Y838661D01*
Y835000D01*
G01Y838661D02*
X856150Y839293D01*
X856623Y839797D01*
X857286Y840050D01*
X857949Y839797D01*
X858422Y839293D01*
X858706Y838535D01*
Y835000D01*
G01X861073D02*
X863440Y842575D01*
X865808Y835000D01*
G01X864955Y837651D02*
X861925D01*
G01X869690Y833106D02*
X870353Y832601D01*
X871110Y832475D01*
X871773Y832601D01*
X872341Y833232D01*
X872720Y834116D01*
Y840050D01*
G01Y839040D02*
X872341Y839545D01*
X871773Y839924D01*
X871110Y840050D01*
X870353Y839797D01*
X869879Y839293D01*
X869500Y838409D01*
X869311Y837525D01*
X869406Y836767D01*
X869785Y835884D01*
X870353Y835252D01*
X871110Y835000D01*
X871678Y835126D01*
X872341Y835631D01*
X872720Y836136D01*
G01X879064Y832475D02*
X880011Y833738D01*
X880484Y835000D01*
Y840050D01*
X880011Y841313D01*
X879064Y842575D01*
G01X499947Y823000D02*
Y830575D01*
X502219D01*
X502977Y830196D01*
X503545Y829313D01*
X503734Y828303D01*
X503545Y827293D01*
X503071Y826535D01*
X502219Y826156D01*
X499947D01*
G01X509415Y830575D02*
Y823000D01*
G01X507238Y830575D02*
X511593D01*
G01X515002Y823000D02*
Y830575D01*
G01X518979D02*
Y823000D01*
G01Y826787D02*
X515002D01*
G01X530531Y823000D02*
Y830575D01*
G01Y826914D02*
X531004Y827545D01*
X531478Y827924D01*
X532235Y828050D01*
X532803Y827924D01*
X533466Y827419D01*
X533750Y826661D01*
Y823000D01*
G01X539715D02*
X539147Y823126D01*
X538579Y823631D01*
X538200Y824515D01*
X538011Y825525D01*
X538200Y826535D01*
X538579Y827419D01*
X539147Y827924D01*
X539715Y828050D01*
X540284Y827924D01*
X540852Y827419D01*
X541230Y826535D01*
X541325Y825525D01*
X541230Y824515D01*
X540852Y823631D01*
X540284Y823126D01*
X539715Y823000D01*
G01X547290D02*
Y830575D01*
G01X553445Y826409D02*
X556475D01*
X556191Y827293D01*
X555718Y827797D01*
X555055Y828050D01*
X554392Y827924D01*
X553824Y827545D01*
X553445Y826661D01*
X553256Y825904D01*
Y825146D01*
X553445Y824389D01*
X553919Y823631D01*
X554487Y823126D01*
X555150Y823000D01*
X555812Y823252D01*
X556475Y824010D01*
G01X569447Y823000D02*
Y829439D01*
X569637Y830070D01*
X570015Y830449D01*
X570584Y830575D01*
X571152Y830323D01*
X571436Y829691D01*
G01X570300Y827545D02*
X568406D01*
G01X577590Y823000D02*
X577022Y823126D01*
X576454Y823631D01*
X576075Y824515D01*
X575886Y825525D01*
X576075Y826535D01*
X576454Y827419D01*
X577022Y827924D01*
X577590Y828050D01*
X578159Y827924D01*
X578727Y827419D01*
X579105Y826535D01*
X579200Y825525D01*
X579105Y824515D01*
X578727Y823631D01*
X578159Y823126D01*
X577590Y823000D01*
G01X583840D02*
Y828050D01*
G01Y827040D02*
X584313Y827545D01*
X584787Y827924D01*
X585450Y828050D01*
X585923Y827924D01*
X586491Y827545D01*
G01X601830Y827419D02*
X601168Y827924D01*
X600600Y828050D01*
X599842Y827797D01*
X599274Y827293D01*
X598895Y826409D01*
X598800Y825525D01*
X598895Y824641D01*
X599274Y823884D01*
X599842Y823252D01*
X600600Y823000D01*
X601262Y823252D01*
X601830Y823757D01*
G01X607890Y823000D02*
X607322Y823126D01*
X606754Y823631D01*
X606375Y824515D01*
X606186Y825525D01*
X606375Y826535D01*
X606754Y827419D01*
X607322Y827924D01*
X607890Y828050D01*
X608459Y827924D01*
X609027Y827419D01*
X609405Y826535D01*
X609500Y825525D01*
X609405Y824515D01*
X609027Y823631D01*
X608459Y823126D01*
X607890Y823000D01*
G01X612625D02*
Y828050D01*
G01Y826661D02*
X612909Y827293D01*
X613382Y827797D01*
X614045Y828050D01*
X614708Y827797D01*
X615181Y827293D01*
X615465Y826661D01*
Y823000D01*
G01Y826661D02*
X615750Y827293D01*
X616223Y827797D01*
X616886Y828050D01*
X617549Y827797D01*
X618022Y827293D01*
X618306Y826535D01*
Y823000D01*
G01X621336Y820475D02*
Y828050D01*
G01Y826914D02*
X621810Y827545D01*
X622283Y827924D01*
X623040Y828050D01*
X623703Y827924D01*
X624366Y827293D01*
X624650Y826409D01*
X624745Y825525D01*
X624650Y824641D01*
X624366Y823757D01*
X623798Y823252D01*
X623040Y823000D01*
X622378Y823126D01*
X621715Y823505D01*
X621336Y824010D01*
G01X630615Y823000D02*
X630047Y823126D01*
X629479Y823631D01*
X629100Y824515D01*
X628911Y825525D01*
X629100Y826535D01*
X629479Y827419D01*
X630047Y827924D01*
X630615Y828050D01*
X631184Y827924D01*
X631752Y827419D01*
X632130Y826535D01*
X632225Y825525D01*
X632130Y824515D01*
X631752Y823631D01*
X631184Y823126D01*
X630615Y823000D01*
G01X636581D02*
Y828050D01*
G01Y826787D02*
X636960Y827419D01*
X637528Y827924D01*
X638285Y828050D01*
X638948Y827924D01*
X639516Y827419D01*
X639800Y826535D01*
Y823000D01*
G01X644345Y826409D02*
X647375D01*
X647091Y827293D01*
X646618Y827797D01*
X645955Y828050D01*
X645292Y827924D01*
X644724Y827545D01*
X644345Y826661D01*
X644156Y825904D01*
Y825146D01*
X644345Y824389D01*
X644819Y823631D01*
X645387Y823126D01*
X646050Y823000D01*
X646712Y823252D01*
X647375Y824010D01*
G01X651731Y823000D02*
Y828050D01*
G01Y826787D02*
X652110Y827419D01*
X652678Y827924D01*
X653435Y828050D01*
X654098Y827924D01*
X654666Y827419D01*
X654950Y826535D01*
Y823000D01*
G01X660915Y830575D02*
Y823000D01*
G01X659590Y828050D02*
X662241D01*
G01X675592Y820475D02*
X674645Y821738D01*
X674172Y823000D01*
Y828050D01*
X674645Y829313D01*
X675592Y830575D01*
G01X683640Y823000D02*
Y830575D01*
X682504Y829060D01*
G01Y823000D02*
X684777D01*
G01X689416Y826156D02*
X690079Y827040D01*
X690647Y827545D01*
X691405Y827797D01*
X692068Y827545D01*
X692541Y827040D01*
X692920Y826282D01*
X693015Y825399D01*
X692920Y824641D01*
X692541Y823884D01*
X691973Y823252D01*
X691310Y823000D01*
X690553Y823252D01*
X689890Y824010D01*
X689511Y825146D01*
X689416Y826409D01*
X689606Y828050D01*
X689890Y828934D01*
X690363Y829817D01*
X691026Y830449D01*
X691689Y830575D01*
X692352Y830323D01*
X692825Y829691D01*
G01X695950Y823000D02*
Y828050D01*
G01Y826661D02*
X696234Y827293D01*
X696707Y827797D01*
X697370Y828050D01*
X698033Y827797D01*
X698506Y827293D01*
X698790Y826661D01*
Y823000D01*
G01Y826661D02*
X699075Y827293D01*
X699548Y827797D01*
X700211Y828050D01*
X700874Y827797D01*
X701347Y827293D01*
X701631Y826535D01*
Y823000D01*
G01X706365Y828050D02*
Y823000D01*
G01Y830070D02*
X706176Y830196D01*
Y830449D01*
X706365Y830575D01*
X706555Y830449D01*
Y830196D01*
X706365Y830070D01*
G01X713940Y823000D02*
Y830575D01*
G01X730984Y823000D02*
X727197Y825525D01*
X730984Y828050D01*
G01X742820Y823884D02*
X743294Y823379D01*
X743956Y823000D01*
X744525D01*
X745093Y823252D01*
X745471Y823631D01*
X745661Y824136D01*
X745566Y824894D01*
X745187Y825272D01*
X743483Y826030D01*
X743104Y826914D01*
X743294Y827545D01*
X743672Y827924D01*
X744240Y828050D01*
X744809Y827924D01*
X745377Y827545D01*
G01X751815Y828050D02*
Y823000D01*
G01Y830070D02*
X751626Y830196D01*
Y830449D01*
X751815Y830575D01*
X752005Y830449D01*
Y830196D01*
X751815Y830070D01*
G01X757970Y828050D02*
X760811D01*
X757970Y823000D01*
X760811D01*
G01X765545Y826409D02*
X768575D01*
X768291Y827293D01*
X767818Y827797D01*
X767155Y828050D01*
X766492Y827924D01*
X765924Y827545D01*
X765545Y826661D01*
X765356Y825904D01*
Y825146D01*
X765545Y824389D01*
X766019Y823631D01*
X766587Y823126D01*
X767250Y823000D01*
X767912Y823252D01*
X768575Y824010D01*
G01X784009Y823000D02*
X780222Y825525D01*
X784009Y828050D01*
G01X789690Y823000D02*
Y830575D01*
X788554Y829060D01*
G01Y823000D02*
X790827D01*
G01X795656Y823884D02*
X796319Y823252D01*
X797076Y823000D01*
X797834Y823252D01*
X798496Y824010D01*
X798970Y825146D01*
X799159Y826282D01*
Y827671D01*
X798970Y828807D01*
X798496Y829817D01*
X797928Y830323D01*
X797265Y830575D01*
X796508Y830323D01*
X795940Y829817D01*
X795561Y829060D01*
X795372Y828050D01*
X795561Y827166D01*
X796035Y826282D01*
X796603Y825777D01*
X797265Y825651D01*
X798023Y825904D01*
X798591Y826535D01*
X799159Y827671D01*
G01X804651Y823000D02*
X804840Y824641D01*
X805125Y826030D01*
X805503Y827293D01*
X805977Y828681D01*
X806734Y830575D01*
X802947D01*
G01X809575Y823000D02*
Y828050D01*
G01Y826661D02*
X809859Y827293D01*
X810332Y827797D01*
X810995Y828050D01*
X811658Y827797D01*
X812131Y827293D01*
X812415Y826661D01*
Y823000D01*
G01Y826661D02*
X812700Y827293D01*
X813173Y827797D01*
X813836Y828050D01*
X814499Y827797D01*
X814972Y827293D01*
X815256Y826535D01*
Y823000D01*
G01X819990Y828050D02*
Y823000D01*
G01Y830070D02*
X819801Y830196D01*
Y830449D01*
X819990Y830575D01*
X820180Y830449D01*
Y830196D01*
X819990Y830070D01*
G01X827565Y823000D02*
Y830575D01*
G01X835614Y820475D02*
X836561Y821738D01*
X837034Y823000D01*
Y828050D01*
X836561Y829313D01*
X835614Y830575D01*
G01X498947Y868075D02*
Y860500D01*
X502734D01*
G01X510120D02*
Y865550D01*
G01Y864666D02*
X509741Y865171D01*
X509173Y865424D01*
X508510Y865550D01*
X507847Y865297D01*
X507279Y864793D01*
X506900Y864035D01*
X506711Y863025D01*
X506900Y862015D01*
X507279Y861257D01*
X507847Y860752D01*
X508510Y860500D01*
X509173Y860626D01*
X509741Y861005D01*
X510120Y861510D01*
G01X514570Y861384D02*
X515044Y860879D01*
X515706Y860500D01*
X516275D01*
X516843Y860752D01*
X517221Y861131D01*
X517411Y861636D01*
X517316Y862394D01*
X516937Y862772D01*
X515233Y863530D01*
X514854Y864414D01*
X515044Y865045D01*
X515422Y865424D01*
X515990Y865550D01*
X516559Y865424D01*
X517127Y865045D01*
G01X522145Y863909D02*
X525175D01*
X524891Y864793D01*
X524418Y865297D01*
X523755Y865550D01*
X523092Y865424D01*
X522524Y865045D01*
X522145Y864161D01*
X521956Y863404D01*
Y862646D01*
X522145Y861889D01*
X522619Y861131D01*
X523187Y860626D01*
X523850Y860500D01*
X524512Y860752D01*
X525175Y861510D01*
G01X529815Y860500D02*
Y865550D01*
G01Y864540D02*
X530288Y865045D01*
X530762Y865424D01*
X531425Y865550D01*
X531898Y865424D01*
X532466Y865045D01*
G01X544586Y865550D02*
X546290Y860500D01*
X547995Y865550D01*
G01X553865D02*
Y860500D01*
G01Y867570D02*
X553676Y867696D01*
Y867949D01*
X553865Y868075D01*
X554055Y867949D01*
Y867696D01*
X553865Y867570D01*
G01X563145Y860500D02*
Y865550D01*
G01Y864666D02*
X562766Y865171D01*
X562198Y865424D01*
X561535Y865550D01*
X560872Y865297D01*
X560304Y864793D01*
X559925Y864035D01*
X559736Y863025D01*
X559925Y862015D01*
X560304Y861257D01*
X560872Y860752D01*
X561535Y860500D01*
X562198Y860626D01*
X562766Y861005D01*
X563145Y861510D01*
G01X574981Y860500D02*
Y868075D01*
G01Y864414D02*
X575454Y865045D01*
X575928Y865424D01*
X576685Y865550D01*
X577253Y865424D01*
X577916Y864919D01*
X578200Y864161D01*
Y860500D01*
G01X584165D02*
X583597Y860626D01*
X583029Y861131D01*
X582650Y862015D01*
X582461Y863025D01*
X582650Y864035D01*
X583029Y864919D01*
X583597Y865424D01*
X584165Y865550D01*
X584734Y865424D01*
X585302Y864919D01*
X585680Y864035D01*
X585775Y863025D01*
X585680Y862015D01*
X585302Y861131D01*
X584734Y860626D01*
X584165Y860500D01*
G01X591740D02*
Y868075D01*
G01X597895Y863909D02*
X600925D01*
X600641Y864793D01*
X600168Y865297D01*
X599505Y865550D01*
X598842Y865424D01*
X598274Y865045D01*
X597895Y864161D01*
X597706Y863404D01*
Y862646D01*
X597895Y861889D01*
X598369Y861131D01*
X598937Y860626D01*
X599600Y860500D01*
X600262Y860752D01*
X600925Y861510D01*
G01X613992Y857975D02*
X613045Y859238D01*
X612572Y860500D01*
Y865550D01*
X613045Y866813D01*
X613992Y868075D01*
G01X620336Y860500D02*
Y868075D01*
G01Y864287D02*
X620810Y865045D01*
X621378Y865424D01*
X621946Y865550D01*
X622798Y865297D01*
X623366Y864793D01*
X623745Y863909D01*
Y862899D01*
X623555Y861889D01*
X623177Y861131D01*
X622514Y860626D01*
X621946Y860500D01*
X621378Y860626D01*
X620810Y861005D01*
X620336Y861636D01*
G01X628195Y863909D02*
X631225D01*
X630941Y864793D01*
X630468Y865297D01*
X629805Y865550D01*
X629142Y865424D01*
X628574Y865045D01*
X628195Y864161D01*
X628006Y863404D01*
Y862646D01*
X628195Y861889D01*
X628669Y861131D01*
X629237Y860626D01*
X629900Y860500D01*
X630562Y860752D01*
X631225Y861510D01*
G01X636622Y860500D02*
Y866939D01*
X636812Y867570D01*
X637190Y867949D01*
X637759Y868075D01*
X638327Y867823D01*
X638611Y867191D01*
G01X637475Y865045D02*
X635581D01*
G01X644765Y860500D02*
X644197Y860626D01*
X643629Y861131D01*
X643250Y862015D01*
X643061Y863025D01*
X643250Y864035D01*
X643629Y864919D01*
X644197Y865424D01*
X644765Y865550D01*
X645334Y865424D01*
X645902Y864919D01*
X646280Y864035D01*
X646375Y863025D01*
X646280Y862015D01*
X645902Y861131D01*
X645334Y860626D01*
X644765Y860500D01*
G01X651015D02*
Y865550D01*
G01Y864540D02*
X651488Y865045D01*
X651962Y865424D01*
X652625Y865550D01*
X653098Y865424D01*
X653666Y865045D01*
G01X658495Y863909D02*
X661525D01*
X661241Y864793D01*
X660768Y865297D01*
X660105Y865550D01*
X659442Y865424D01*
X658874Y865045D01*
X658495Y864161D01*
X658306Y863404D01*
Y862646D01*
X658495Y861889D01*
X658969Y861131D01*
X659537Y860626D01*
X660200Y860500D01*
X660862Y860752D01*
X661525Y861510D01*
G01X675065Y868075D02*
Y860500D01*
G01X673740Y865550D02*
X676391D01*
G01X681031Y860500D02*
Y868075D01*
G01Y864414D02*
X681504Y865045D01*
X681978Y865424D01*
X682735Y865550D01*
X683303Y865424D01*
X683966Y864919D01*
X684250Y864161D01*
Y860500D01*
G01X688795Y863909D02*
X691825D01*
X691541Y864793D01*
X691068Y865297D01*
X690405Y865550D01*
X689742Y865424D01*
X689174Y865045D01*
X688795Y864161D01*
X688606Y863404D01*
Y862646D01*
X688795Y861889D01*
X689269Y861131D01*
X689837Y860626D01*
X690500Y860500D01*
X691162Y860752D01*
X691825Y861510D01*
G01X706880Y864919D02*
X706218Y865424D01*
X705650Y865550D01*
X704892Y865297D01*
X704324Y864793D01*
X703945Y863909D01*
X703850Y863025D01*
X703945Y862141D01*
X704324Y861384D01*
X704892Y860752D01*
X705650Y860500D01*
X706312Y860752D01*
X706880Y861257D01*
G01X712940Y860500D02*
X712372Y860626D01*
X711804Y861131D01*
X711425Y862015D01*
X711236Y863025D01*
X711425Y864035D01*
X711804Y864919D01*
X712372Y865424D01*
X712940Y865550D01*
X713509Y865424D01*
X714077Y864919D01*
X714455Y864035D01*
X714550Y863025D01*
X714455Y862015D01*
X714077Y861131D01*
X713509Y860626D01*
X712940Y860500D01*
G01X718811Y857975D02*
Y865550D01*
G01Y864414D02*
X719285Y865045D01*
X719758Y865424D01*
X720515Y865550D01*
X721178Y865424D01*
X721841Y864793D01*
X722125Y863909D01*
X722220Y863025D01*
X722125Y862141D01*
X721841Y861257D01*
X721273Y860752D01*
X720515Y860500D01*
X719853Y860626D01*
X719190Y861005D01*
X718811Y861510D01*
G01X726386Y857975D02*
Y865550D01*
G01Y864414D02*
X726860Y865045D01*
X727333Y865424D01*
X728090Y865550D01*
X728753Y865424D01*
X729416Y864793D01*
X729700Y863909D01*
X729795Y863025D01*
X729700Y862141D01*
X729416Y861257D01*
X728848Y860752D01*
X728090Y860500D01*
X727428Y860626D01*
X726765Y861005D01*
X726386Y861510D01*
G01X734245Y863909D02*
X737275D01*
X736991Y864793D01*
X736518Y865297D01*
X735855Y865550D01*
X735192Y865424D01*
X734624Y865045D01*
X734245Y864161D01*
X734056Y863404D01*
Y862646D01*
X734245Y861889D01*
X734719Y861131D01*
X735287Y860626D01*
X735950Y860500D01*
X736612Y860752D01*
X737275Y861510D01*
G01X741915Y860500D02*
Y865550D01*
G01Y864540D02*
X742388Y865045D01*
X742862Y865424D01*
X743525Y865550D01*
X743998Y865424D01*
X744566Y865045D01*
G01X756686Y857975D02*
Y865550D01*
G01Y864414D02*
X757160Y865045D01*
X757633Y865424D01*
X758390Y865550D01*
X759053Y865424D01*
X759716Y864793D01*
X760000Y863909D01*
X760095Y863025D01*
X760000Y862141D01*
X759716Y861257D01*
X759148Y860752D01*
X758390Y860500D01*
X757728Y860626D01*
X757065Y861005D01*
X756686Y861510D01*
G01X765965Y860500D02*
Y868075D01*
G01X775245Y860500D02*
Y865550D01*
G01Y864666D02*
X774866Y865171D01*
X774298Y865424D01*
X773635Y865550D01*
X772972Y865297D01*
X772404Y864793D01*
X772025Y864035D01*
X771836Y863025D01*
X772025Y862015D01*
X772404Y861257D01*
X772972Y860752D01*
X773635Y860500D01*
X774298Y860626D01*
X774866Y861005D01*
X775245Y861510D01*
G01X781115Y868075D02*
Y860500D01*
G01X779790Y865550D02*
X782441D01*
G01X788690D02*
Y860500D01*
G01Y867570D02*
X788501Y867696D01*
Y867949D01*
X788690Y868075D01*
X788880Y867949D01*
Y867696D01*
X788690Y867570D01*
G01X794656Y860500D02*
Y865550D01*
G01Y864287D02*
X795035Y864919D01*
X795603Y865424D01*
X796360Y865550D01*
X797023Y865424D01*
X797591Y864919D01*
X797875Y864035D01*
Y860500D01*
G01X802515Y858606D02*
X803178Y858101D01*
X803935Y857975D01*
X804598Y858101D01*
X805166Y858732D01*
X805545Y859616D01*
Y865550D01*
G01Y864540D02*
X805166Y865045D01*
X804598Y865424D01*
X803935Y865550D01*
X803178Y865297D01*
X802704Y864793D01*
X802325Y863909D01*
X802136Y863025D01*
X802231Y862267D01*
X802610Y861384D01*
X803178Y860752D01*
X803935Y860500D01*
X804503Y860626D01*
X805166Y861131D01*
X805545Y861636D01*
G01X811889Y857975D02*
X812836Y859238D01*
X813309Y860500D01*
Y865550D01*
X812836Y866813D01*
X811889Y868075D01*
G01X499447Y848000D02*
Y855575D01*
X501719D01*
X502477Y855196D01*
X503045Y854313D01*
X503234Y853303D01*
X503045Y852293D01*
X502571Y851535D01*
X501719Y851156D01*
X499447D01*
G01X508915Y855575D02*
Y848000D01*
G01X506738Y855575D02*
X511093D01*
G01X514502Y848000D02*
Y855575D01*
G01X518479D02*
Y848000D01*
G01Y851787D02*
X514502D01*
G01X530031Y848000D02*
Y855575D01*
G01Y851914D02*
X530504Y852545D01*
X530978Y852924D01*
X531735Y853050D01*
X532303Y852924D01*
X532966Y852419D01*
X533250Y851661D01*
Y848000D01*
G01X539215D02*
X538647Y848126D01*
X538079Y848631D01*
X537700Y849515D01*
X537511Y850525D01*
X537700Y851535D01*
X538079Y852419D01*
X538647Y852924D01*
X539215Y853050D01*
X539784Y852924D01*
X540352Y852419D01*
X540730Y851535D01*
X540825Y850525D01*
X540730Y849515D01*
X540352Y848631D01*
X539784Y848126D01*
X539215Y848000D01*
G01X546790D02*
Y855575D01*
G01X552945Y851409D02*
X555975D01*
X555691Y852293D01*
X555218Y852797D01*
X554555Y853050D01*
X553892Y852924D01*
X553324Y852545D01*
X552945Y851661D01*
X552756Y850904D01*
Y850146D01*
X552945Y849389D01*
X553419Y848631D01*
X553987Y848126D01*
X554650Y848000D01*
X555312Y848252D01*
X555975Y849010D01*
G01X568947Y848000D02*
Y854439D01*
X569137Y855070D01*
X569515Y855449D01*
X570084Y855575D01*
X570652Y855323D01*
X570936Y854691D01*
G01X569800Y852545D02*
X567906D01*
G01X577090Y848000D02*
X576522Y848126D01*
X575954Y848631D01*
X575575Y849515D01*
X575386Y850525D01*
X575575Y851535D01*
X575954Y852419D01*
X576522Y852924D01*
X577090Y853050D01*
X577659Y852924D01*
X578227Y852419D01*
X578605Y851535D01*
X578700Y850525D01*
X578605Y849515D01*
X578227Y848631D01*
X577659Y848126D01*
X577090Y848000D01*
G01X583340D02*
Y853050D01*
G01Y852040D02*
X583813Y852545D01*
X584287Y852924D01*
X584950Y853050D01*
X585423Y852924D01*
X585991Y852545D01*
G01X601330Y852419D02*
X600668Y852924D01*
X600100Y853050D01*
X599342Y852797D01*
X598774Y852293D01*
X598395Y851409D01*
X598300Y850525D01*
X598395Y849641D01*
X598774Y848884D01*
X599342Y848252D01*
X600100Y848000D01*
X600762Y848252D01*
X601330Y848757D01*
G01X607390Y848000D02*
X606822Y848126D01*
X606254Y848631D01*
X605875Y849515D01*
X605686Y850525D01*
X605875Y851535D01*
X606254Y852419D01*
X606822Y852924D01*
X607390Y853050D01*
X607959Y852924D01*
X608527Y852419D01*
X608905Y851535D01*
X609000Y850525D01*
X608905Y849515D01*
X608527Y848631D01*
X607959Y848126D01*
X607390Y848000D01*
G01X612125D02*
Y853050D01*
G01Y851661D02*
X612409Y852293D01*
X612882Y852797D01*
X613545Y853050D01*
X614208Y852797D01*
X614681Y852293D01*
X614965Y851661D01*
Y848000D01*
G01Y851661D02*
X615250Y852293D01*
X615723Y852797D01*
X616386Y853050D01*
X617049Y852797D01*
X617522Y852293D01*
X617806Y851535D01*
Y848000D01*
G01X620836Y845475D02*
Y853050D01*
G01Y851914D02*
X621310Y852545D01*
X621783Y852924D01*
X622540Y853050D01*
X623203Y852924D01*
X623866Y852293D01*
X624150Y851409D01*
X624245Y850525D01*
X624150Y849641D01*
X623866Y848757D01*
X623298Y848252D01*
X622540Y848000D01*
X621878Y848126D01*
X621215Y848505D01*
X620836Y849010D01*
G01X630115Y848000D02*
X629547Y848126D01*
X628979Y848631D01*
X628600Y849515D01*
X628411Y850525D01*
X628600Y851535D01*
X628979Y852419D01*
X629547Y852924D01*
X630115Y853050D01*
X630684Y852924D01*
X631252Y852419D01*
X631630Y851535D01*
X631725Y850525D01*
X631630Y849515D01*
X631252Y848631D01*
X630684Y848126D01*
X630115Y848000D01*
G01X636081D02*
Y853050D01*
G01Y851787D02*
X636460Y852419D01*
X637028Y852924D01*
X637785Y853050D01*
X638448Y852924D01*
X639016Y852419D01*
X639300Y851535D01*
Y848000D01*
G01X643845Y851409D02*
X646875D01*
X646591Y852293D01*
X646118Y852797D01*
X645455Y853050D01*
X644792Y852924D01*
X644224Y852545D01*
X643845Y851661D01*
X643656Y850904D01*
Y850146D01*
X643845Y849389D01*
X644319Y848631D01*
X644887Y848126D01*
X645550Y848000D01*
X646212Y848252D01*
X646875Y849010D01*
G01X651231Y848000D02*
Y853050D01*
G01Y851787D02*
X651610Y852419D01*
X652178Y852924D01*
X652935Y853050D01*
X653598Y852924D01*
X654166Y852419D01*
X654450Y851535D01*
Y848000D01*
G01X660415Y855575D02*
Y848000D01*
G01X659090Y853050D02*
X661741D01*
G01X675092Y845475D02*
X674145Y846738D01*
X673672Y848000D01*
Y853050D01*
X674145Y854313D01*
X675092Y855575D01*
G01X683140Y848000D02*
Y855575D01*
X682004Y854060D01*
G01Y848000D02*
X684277D01*
G01X688916Y851156D02*
X689579Y852040D01*
X690147Y852545D01*
X690905Y852797D01*
X691568Y852545D01*
X692041Y852040D01*
X692420Y851282D01*
X692515Y850399D01*
X692420Y849641D01*
X692041Y848884D01*
X691473Y848252D01*
X690810Y848000D01*
X690053Y848252D01*
X689390Y849010D01*
X689011Y850146D01*
X688916Y851409D01*
X689106Y853050D01*
X689390Y853934D01*
X689863Y854817D01*
X690526Y855449D01*
X691189Y855575D01*
X691852Y855323D01*
X692325Y854691D01*
G01X695450Y848000D02*
Y853050D01*
G01Y851661D02*
X695734Y852293D01*
X696207Y852797D01*
X696870Y853050D01*
X697533Y852797D01*
X698006Y852293D01*
X698290Y851661D01*
Y848000D01*
G01Y851661D02*
X698575Y852293D01*
X699048Y852797D01*
X699711Y853050D01*
X700374Y852797D01*
X700847Y852293D01*
X701131Y851535D01*
Y848000D01*
G01X705865Y853050D02*
Y848000D01*
G01Y855070D02*
X705676Y855196D01*
Y855449D01*
X705865Y855575D01*
X706055Y855449D01*
Y855196D01*
X705865Y855070D01*
G01X713440Y848000D02*
Y855575D01*
G01X730484Y848000D02*
X726697Y850525D01*
X730484Y853050D01*
G01X742320Y848884D02*
X742794Y848379D01*
X743456Y848000D01*
X744025D01*
X744593Y848252D01*
X744971Y848631D01*
X745161Y849136D01*
X745066Y849894D01*
X744687Y850272D01*
X742983Y851030D01*
X742604Y851914D01*
X742794Y852545D01*
X743172Y852924D01*
X743740Y853050D01*
X744309Y852924D01*
X744877Y852545D01*
G01X751315Y853050D02*
Y848000D01*
G01Y855070D02*
X751126Y855196D01*
Y855449D01*
X751315Y855575D01*
X751505Y855449D01*
Y855196D01*
X751315Y855070D01*
G01X757470Y853050D02*
X760311D01*
X757470Y848000D01*
X760311D01*
G01X765045Y851409D02*
X768075D01*
X767791Y852293D01*
X767318Y852797D01*
X766655Y853050D01*
X765992Y852924D01*
X765424Y852545D01*
X765045Y851661D01*
X764856Y850904D01*
Y850146D01*
X765045Y849389D01*
X765519Y848631D01*
X766087Y848126D01*
X766750Y848000D01*
X767412Y848252D01*
X768075Y849010D01*
G01X783509Y848000D02*
X779722Y850525D01*
X783509Y853050D01*
G01X789190Y848000D02*
Y855575D01*
X788054Y854060D01*
G01Y848000D02*
X790327D01*
G01X795156Y848884D02*
X795819Y848252D01*
X796576Y848000D01*
X797334Y848252D01*
X797996Y849010D01*
X798470Y850146D01*
X798659Y851282D01*
Y852671D01*
X798470Y853807D01*
X797996Y854817D01*
X797428Y855323D01*
X796765Y855575D01*
X796008Y855323D01*
X795440Y854817D01*
X795061Y854060D01*
X794872Y853050D01*
X795061Y852166D01*
X795535Y851282D01*
X796103Y850777D01*
X796765Y850651D01*
X797523Y850904D01*
X798091Y851535D01*
X798659Y852671D01*
G01X804151Y848000D02*
X804340Y849641D01*
X804625Y851030D01*
X805003Y852293D01*
X805477Y853681D01*
X806234Y855575D01*
X802447D01*
G01X809075Y848000D02*
Y853050D01*
G01Y851661D02*
X809359Y852293D01*
X809832Y852797D01*
X810495Y853050D01*
X811158Y852797D01*
X811631Y852293D01*
X811915Y851661D01*
Y848000D01*
G01Y851661D02*
X812200Y852293D01*
X812673Y852797D01*
X813336Y853050D01*
X813999Y852797D01*
X814472Y852293D01*
X814756Y851535D01*
Y848000D01*
G01X819490Y853050D02*
Y848000D01*
G01Y855070D02*
X819301Y855196D01*
Y855449D01*
X819490Y855575D01*
X819680Y855449D01*
Y855196D01*
X819490Y855070D01*
G01X827065Y848000D02*
Y855575D01*
G01X835114Y845475D02*
X836061Y846738D01*
X836534Y848000D01*
Y853050D01*
X836061Y854313D01*
X835114Y855575D01*
G01X498473Y880575D02*
X500840Y873000D01*
X503208Y880575D01*
G01X508415Y878050D02*
Y873000D01*
G01Y880070D02*
X508226Y880196D01*
Y880449D01*
X508415Y880575D01*
X508605Y880449D01*
Y880196D01*
X508415Y880070D01*
G01X517695Y873000D02*
Y878050D01*
G01Y877166D02*
X517316Y877671D01*
X516748Y877924D01*
X516085Y878050D01*
X515422Y877797D01*
X514854Y877293D01*
X514475Y876535D01*
X514286Y875525D01*
X514475Y874515D01*
X514854Y873757D01*
X515422Y873252D01*
X516085Y873000D01*
X516748Y873126D01*
X517316Y873505D01*
X517695Y874010D01*
G01X529152Y873000D02*
Y880575D01*
G01X533129D02*
Y873000D01*
G01Y876787D02*
X529152D01*
G01X538715Y873000D02*
X538147Y873126D01*
X537579Y873631D01*
X537200Y874515D01*
X537011Y875525D01*
X537200Y876535D01*
X537579Y877419D01*
X538147Y877924D01*
X538715Y878050D01*
X539284Y877924D01*
X539852Y877419D01*
X540230Y876535D01*
X540325Y875525D01*
X540230Y874515D01*
X539852Y873631D01*
X539284Y873126D01*
X538715Y873000D01*
G01X546290D02*
Y880575D01*
G01X552445Y876409D02*
X555475D01*
X555191Y877293D01*
X554718Y877797D01*
X554055Y878050D01*
X553392Y877924D01*
X552824Y877545D01*
X552445Y876661D01*
X552256Y875904D01*
Y875146D01*
X552445Y874389D01*
X552919Y873631D01*
X553487Y873126D01*
X554150Y873000D01*
X554812Y873252D01*
X555475Y874010D01*
G01X568542Y870475D02*
X567595Y871738D01*
X567122Y873000D01*
Y878050D01*
X567595Y879313D01*
X568542Y880575D01*
G01X574981Y873000D02*
Y880575D01*
G01Y876914D02*
X575454Y877545D01*
X575928Y877924D01*
X576685Y878050D01*
X577253Y877924D01*
X577916Y877419D01*
X578200Y876661D01*
Y873000D01*
G01X584165D02*
X583597Y873126D01*
X583029Y873631D01*
X582650Y874515D01*
X582461Y875525D01*
X582650Y876535D01*
X583029Y877419D01*
X583597Y877924D01*
X584165Y878050D01*
X584734Y877924D01*
X585302Y877419D01*
X585680Y876535D01*
X585775Y875525D01*
X585680Y874515D01*
X585302Y873631D01*
X584734Y873126D01*
X584165Y873000D01*
G01X591740D02*
Y880575D01*
G01X597895Y876409D02*
X600925D01*
X600641Y877293D01*
X600168Y877797D01*
X599505Y878050D01*
X598842Y877924D01*
X598274Y877545D01*
X597895Y876661D01*
X597706Y875904D01*
Y875146D01*
X597895Y874389D01*
X598369Y873631D01*
X598937Y873126D01*
X599600Y873000D01*
X600262Y873252D01*
X600925Y874010D01*
G01X613045Y873884D02*
X613519Y873379D01*
X614181Y873000D01*
X614750D01*
X615318Y873252D01*
X615696Y873631D01*
X615886Y874136D01*
X615791Y874894D01*
X615412Y875272D01*
X613708Y876030D01*
X613329Y876914D01*
X613519Y877545D01*
X613897Y877924D01*
X614465Y878050D01*
X615034Y877924D01*
X615602Y877545D01*
G01X622040Y878050D02*
Y873000D01*
G01Y880070D02*
X621851Y880196D01*
Y880449D01*
X622040Y880575D01*
X622230Y880449D01*
Y880196D01*
X622040Y880070D01*
G01X628195Y878050D02*
X631036D01*
X628195Y873000D01*
X631036D01*
G01X635770Y876409D02*
X638800D01*
X638516Y877293D01*
X638043Y877797D01*
X637380Y878050D01*
X636717Y877924D01*
X636149Y877545D01*
X635770Y876661D01*
X635581Y875904D01*
Y875146D01*
X635770Y874389D01*
X636244Y873631D01*
X636812Y873126D01*
X637475Y873000D01*
X638137Y873252D01*
X638800Y874010D01*
G01X654234Y873000D02*
X650447Y875525D01*
X654234Y878050D01*
G01X658685Y874389D02*
X661146D01*
G01Y876661D02*
X658685D01*
G01X667490Y873000D02*
Y880575D01*
X666354Y879060D01*
G01Y873000D02*
X668627D01*
G01X673266Y876156D02*
X673929Y877040D01*
X674497Y877545D01*
X675255Y877797D01*
X675918Y877545D01*
X676391Y877040D01*
X676770Y876282D01*
X676865Y875399D01*
X676770Y874641D01*
X676391Y873884D01*
X675823Y873252D01*
X675160Y873000D01*
X674403Y873252D01*
X673740Y874010D01*
X673361Y875146D01*
X673266Y876409D01*
X673456Y878050D01*
X673740Y878934D01*
X674213Y879817D01*
X674876Y880449D01*
X675539Y880575D01*
X676202Y880323D01*
X676675Y879691D01*
G01X687375Y873000D02*
Y878050D01*
G01Y876661D02*
X687659Y877293D01*
X688132Y877797D01*
X688795Y878050D01*
X689458Y877797D01*
X689931Y877293D01*
X690215Y876661D01*
Y873000D01*
G01Y876661D02*
X690500Y877293D01*
X690973Y877797D01*
X691636Y878050D01*
X692299Y877797D01*
X692772Y877293D01*
X693056Y876535D01*
Y873000D01*
G01X697790Y878050D02*
Y873000D01*
G01Y880070D02*
X697601Y880196D01*
Y880449D01*
X697790Y880575D01*
X697980Y880449D01*
Y880196D01*
X697790Y880070D01*
G01X705365Y873000D02*
Y880575D01*
G01X713414Y870475D02*
X714361Y871738D01*
X714834Y873000D01*
Y878050D01*
X714361Y879313D01*
X713414Y880575D01*
G01X513340Y893075D02*
Y885500D01*
G01X512015Y890550D02*
X514666D01*
G01X519306Y885500D02*
Y893075D01*
G01Y889414D02*
X519779Y890045D01*
X520253Y890424D01*
X521010Y890550D01*
X521578Y890424D01*
X522241Y889919D01*
X522525Y889161D01*
Y885500D01*
G01X527070Y888909D02*
X530100D01*
X529816Y889793D01*
X529343Y890297D01*
X528680Y890550D01*
X528017Y890424D01*
X527449Y890045D01*
X527070Y889161D01*
X526881Y888404D01*
Y887646D01*
X527070Y886889D01*
X527544Y886131D01*
X528112Y885626D01*
X528775Y885500D01*
X529437Y885752D01*
X530100Y886510D01*
G01X542315Y885500D02*
Y890550D01*
G01Y889540D02*
X542788Y890045D01*
X543262Y890424D01*
X543925Y890550D01*
X544398Y890424D01*
X544966Y890045D01*
G01X549795Y888909D02*
X552825D01*
X552541Y889793D01*
X552068Y890297D01*
X551405Y890550D01*
X550742Y890424D01*
X550174Y890045D01*
X549795Y889161D01*
X549606Y888404D01*
Y887646D01*
X549795Y886889D01*
X550269Y886131D01*
X550837Y885626D01*
X551500Y885500D01*
X552162Y885752D01*
X552825Y886510D01*
G01X558790Y885500D02*
Y893075D01*
G01X568070Y885500D02*
Y890550D01*
G01Y889666D02*
X567691Y890171D01*
X567123Y890424D01*
X566460Y890550D01*
X565797Y890297D01*
X565229Y889793D01*
X564850Y889035D01*
X564661Y888025D01*
X564850Y887015D01*
X565229Y886257D01*
X565797Y885752D01*
X566460Y885500D01*
X567123Y885626D01*
X567691Y886005D01*
X568070Y886510D01*
G01X573940Y893075D02*
Y885500D01*
G01X572615Y890550D02*
X575266D01*
G01X581515D02*
Y885500D01*
G01Y892570D02*
X581326Y892696D01*
Y892949D01*
X581515Y893075D01*
X581705Y892949D01*
Y892696D01*
X581515Y892570D01*
G01X587386Y890550D02*
X589090Y885500D01*
X590795Y890550D01*
G01X595245Y888909D02*
X598275D01*
X597991Y889793D01*
X597518Y890297D01*
X596855Y890550D01*
X596192Y890424D01*
X595624Y890045D01*
X595245Y889161D01*
X595056Y888404D01*
Y887646D01*
X595245Y886889D01*
X595719Y886131D01*
X596287Y885626D01*
X596950Y885500D01*
X597612Y885752D01*
X598275Y886510D01*
G01X611815Y885500D02*
Y893075D01*
G01X619390Y885500D02*
X618822Y885626D01*
X618254Y886131D01*
X617875Y887015D01*
X617686Y888025D01*
X617875Y889035D01*
X618254Y889919D01*
X618822Y890424D01*
X619390Y890550D01*
X619959Y890424D01*
X620527Y889919D01*
X620905Y889035D01*
X621000Y888025D01*
X620905Y887015D01*
X620527Y886131D01*
X619959Y885626D01*
X619390Y885500D01*
G01X628480Y889919D02*
X627818Y890424D01*
X627250Y890550D01*
X626492Y890297D01*
X625924Y889793D01*
X625545Y888909D01*
X625450Y888025D01*
X625545Y887141D01*
X625924Y886384D01*
X626492Y885752D01*
X627250Y885500D01*
X627912Y885752D01*
X628480Y886257D01*
G01X636245Y885500D02*
Y890550D01*
G01Y889666D02*
X635866Y890171D01*
X635298Y890424D01*
X634635Y890550D01*
X633972Y890297D01*
X633404Y889793D01*
X633025Y889035D01*
X632836Y888025D01*
X633025Y887015D01*
X633404Y886257D01*
X633972Y885752D01*
X634635Y885500D01*
X635298Y885626D01*
X635866Y886005D01*
X636245Y886510D01*
G01X642115Y893075D02*
Y885500D01*
G01X640790Y890550D02*
X643441D01*
G01X649690D02*
Y885500D01*
G01Y892570D02*
X649501Y892696D01*
Y892949D01*
X649690Y893075D01*
X649880Y892949D01*
Y892696D01*
X649690Y892570D01*
G01X657265Y885500D02*
X656697Y885626D01*
X656129Y886131D01*
X655750Y887015D01*
X655561Y888025D01*
X655750Y889035D01*
X656129Y889919D01*
X656697Y890424D01*
X657265Y890550D01*
X657834Y890424D01*
X658402Y889919D01*
X658780Y889035D01*
X658875Y888025D01*
X658780Y887015D01*
X658402Y886131D01*
X657834Y885626D01*
X657265Y885500D01*
G01X663231D02*
Y890550D01*
G01Y889287D02*
X663610Y889919D01*
X664178Y890424D01*
X664935Y890550D01*
X665598Y890424D01*
X666166Y889919D01*
X666450Y889035D01*
Y885500D01*
G01X679990D02*
X679422Y885626D01*
X678854Y886131D01*
X678475Y887015D01*
X678286Y888025D01*
X678475Y889035D01*
X678854Y889919D01*
X679422Y890424D01*
X679990Y890550D01*
X680559Y890424D01*
X681127Y889919D01*
X681505Y889035D01*
X681600Y888025D01*
X681505Y887015D01*
X681127Y886131D01*
X680559Y885626D01*
X679990Y885500D01*
G01X686997D02*
Y891939D01*
X687187Y892570D01*
X687565Y892949D01*
X688134Y893075D01*
X688702Y892823D01*
X688986Y892191D01*
G01X687850Y890045D02*
X685956D01*
G01X701106Y885500D02*
Y893075D01*
G01Y889414D02*
X701579Y890045D01*
X702053Y890424D01*
X702810Y890550D01*
X703378Y890424D01*
X704041Y889919D01*
X704325Y889161D01*
Y885500D01*
G01X710290D02*
X709722Y885626D01*
X709154Y886131D01*
X708775Y887015D01*
X708586Y888025D01*
X708775Y889035D01*
X709154Y889919D01*
X709722Y890424D01*
X710290Y890550D01*
X710859Y890424D01*
X711427Y889919D01*
X711805Y889035D01*
X711900Y888025D01*
X711805Y887015D01*
X711427Y886131D01*
X710859Y885626D01*
X710290Y885500D01*
G01X717865D02*
Y893075D01*
G01X724020Y888909D02*
X727050D01*
X726766Y889793D01*
X726293Y890297D01*
X725630Y890550D01*
X724967Y890424D01*
X724399Y890045D01*
X724020Y889161D01*
X723831Y888404D01*
Y887646D01*
X724020Y886889D01*
X724494Y886131D01*
X725062Y885626D01*
X725725Y885500D01*
X726387Y885752D01*
X727050Y886510D01*
G01X740590Y893075D02*
Y885500D01*
G01X739265Y890550D02*
X741916D01*
G01X748165Y885500D02*
X747597Y885626D01*
X747029Y886131D01*
X746650Y887015D01*
X746461Y888025D01*
X746650Y889035D01*
X747029Y889919D01*
X747597Y890424D01*
X748165Y890550D01*
X748734Y890424D01*
X749302Y889919D01*
X749680Y889035D01*
X749775Y888025D01*
X749680Y887015D01*
X749302Y886131D01*
X748734Y885626D01*
X748165Y885500D01*
G01X761706D02*
Y893075D01*
G01Y889414D02*
X762179Y890045D01*
X762653Y890424D01*
X763410Y890550D01*
X763978Y890424D01*
X764641Y889919D01*
X764925Y889161D01*
Y885500D01*
G01X770890D02*
X770322Y885626D01*
X769754Y886131D01*
X769375Y887015D01*
X769186Y888025D01*
X769375Y889035D01*
X769754Y889919D01*
X770322Y890424D01*
X770890Y890550D01*
X771459Y890424D01*
X772027Y889919D01*
X772405Y889035D01*
X772500Y888025D01*
X772405Y887015D01*
X772027Y886131D01*
X771459Y885626D01*
X770890Y885500D01*
G01X778465D02*
Y893075D01*
G01X784620Y888909D02*
X787650D01*
X787366Y889793D01*
X786893Y890297D01*
X786230Y890550D01*
X785567Y890424D01*
X784999Y890045D01*
X784620Y889161D01*
X784431Y888404D01*
Y887646D01*
X784620Y886889D01*
X785094Y886131D01*
X785662Y885626D01*
X786325Y885500D01*
X786987Y885752D01*
X787650Y886510D01*
G01X659704Y907575D02*
X661977D01*
G01X660840D02*
Y900000D01*
G01X659704D02*
X661977D01*
G01X668415Y907575D02*
Y900000D01*
G01X667090Y905050D02*
X669741D01*
G01X674570Y903409D02*
X677600D01*
X677316Y904293D01*
X676843Y904797D01*
X676180Y905050D01*
X675517Y904924D01*
X674949Y904545D01*
X674570Y903661D01*
X674381Y902904D01*
Y902146D01*
X674570Y901389D01*
X675044Y900631D01*
X675612Y900126D01*
X676275Y900000D01*
X676937Y900252D01*
X677600Y901010D01*
G01X680725Y900000D02*
Y905050D01*
G01Y903661D02*
X681009Y904293D01*
X681482Y904797D01*
X682145Y905050D01*
X682808Y904797D01*
X683281Y904293D01*
X683565Y903661D01*
Y900000D01*
G01Y903661D02*
X683850Y904293D01*
X684323Y904797D01*
X684986Y905050D01*
X685649Y904797D01*
X686122Y904293D01*
X686406Y903535D01*
Y900000D01*
G01X689720Y900884D02*
X690194Y900379D01*
X690856Y900000D01*
X691425D01*
X691993Y900252D01*
X692371Y900631D01*
X692561Y901136D01*
X692466Y901894D01*
X692087Y902272D01*
X690383Y903030D01*
X690004Y903914D01*
X690194Y904545D01*
X690572Y904924D01*
X691140Y905050D01*
X691709Y904924D01*
X692277Y904545D01*
G01X913840Y735600D02*
Y743175D01*
X912704Y741660D01*
G01Y735600D02*
X914977D01*
G01X921415Y735348D02*
X921226Y735474D01*
Y735726D01*
X921415Y735852D01*
X921605Y735726D01*
Y735474D01*
X921415Y735348D01*
G01X928990Y743175D02*
X928233Y742923D01*
X927665Y742291D01*
X927286Y741534D01*
X927002Y740524D01*
X926907Y739387D01*
X927002Y738251D01*
X927286Y737241D01*
X927665Y736484D01*
X928233Y735852D01*
X928990Y735600D01*
X929748Y735852D01*
X930316Y736484D01*
X930695Y737241D01*
X930979Y738251D01*
X931074Y739387D01*
X930979Y740524D01*
X930695Y741534D01*
X930316Y742291D01*
X929748Y742923D01*
X928990Y743175D01*
G01X933725Y735600D02*
Y740650D01*
G01Y739261D02*
X934009Y739893D01*
X934482Y740397D01*
X935145Y740650D01*
X935808Y740397D01*
X936281Y739893D01*
X936565Y739261D01*
Y735600D01*
G01Y739261D02*
X936850Y739893D01*
X937323Y740397D01*
X937986Y740650D01*
X938649Y740397D01*
X939122Y739893D01*
X939406Y739135D01*
Y735600D01*
G01X944140Y740650D02*
Y735600D01*
G01Y742670D02*
X943951Y742796D01*
Y743049D01*
X944140Y743175D01*
X944330Y743049D01*
Y742796D01*
X944140Y742670D01*
G01X951715Y735600D02*
Y743175D01*
G01X964025Y735600D02*
Y740650D01*
G01Y739261D02*
X964309Y739893D01*
X964782Y740397D01*
X965445Y740650D01*
X966108Y740397D01*
X966581Y739893D01*
X966865Y739261D01*
Y735600D01*
G01Y739261D02*
X967150Y739893D01*
X967623Y740397D01*
X968286Y740650D01*
X968949Y740397D01*
X969422Y739893D01*
X969706Y739135D01*
Y735600D01*
G01X976145D02*
Y740650D01*
G01Y739766D02*
X975766Y740271D01*
X975198Y740524D01*
X974535Y740650D01*
X973872Y740397D01*
X973304Y739893D01*
X972925Y739135D01*
X972736Y738125D01*
X972925Y737115D01*
X973304Y736357D01*
X973872Y735852D01*
X974535Y735600D01*
X975198Y735726D01*
X975766Y736105D01*
X976145Y736610D01*
G01X980595Y740650D02*
X983436Y735600D01*
G01Y740650D02*
X980595Y735600D01*
G01X924799Y750025D02*
X927071D01*
G01X925840Y751666D02*
Y748384D01*
G01X931711Y747248D02*
X935120Y755075D01*
G01X939760Y750025D02*
X942221D01*
G01X946482Y748636D02*
X947050Y748005D01*
X947713Y747626D01*
X948565Y747500D01*
X949418Y747752D01*
X950080Y748257D01*
X950554Y749141D01*
X950649Y750151D01*
X950459Y751161D01*
X949986Y751793D01*
X949323Y752297D01*
X948660Y752424D01*
X947997Y752297D01*
X947145Y751793D01*
X947429Y755075D01*
X949986D01*
G01X953300Y747500D02*
Y752550D01*
G01Y751161D02*
X953584Y751793D01*
X954057Y752297D01*
X954720Y752550D01*
X955383Y752297D01*
X955856Y751793D01*
X956140Y751161D01*
Y747500D01*
G01Y751161D02*
X956425Y751793D01*
X956898Y752297D01*
X957561Y752550D01*
X958224Y752297D01*
X958697Y751793D01*
X958981Y751035D01*
Y747500D01*
G01X963715Y752550D02*
Y747500D01*
G01Y754570D02*
X963526Y754696D01*
Y754949D01*
X963715Y755075D01*
X963905Y754949D01*
Y754696D01*
X963715Y754570D01*
G01X971290Y747500D02*
Y755075D01*
G01X908299Y787725D02*
X910571D01*
G01X909340Y789366D02*
Y786084D01*
G01X916915Y792775D02*
X916158Y792523D01*
X915590Y791891D01*
X915211Y791134D01*
X914927Y790124D01*
X914832Y788987D01*
X914927Y787851D01*
X915211Y786841D01*
X915590Y786084D01*
X916158Y785452D01*
X916915Y785200D01*
X917673Y785452D01*
X918241Y786084D01*
X918620Y786841D01*
X918904Y787851D01*
X918999Y788987D01*
X918904Y790124D01*
X918620Y791134D01*
X918241Y791891D01*
X917673Y792523D01*
X916915Y792775D01*
G01X924490Y784948D02*
X924301Y785074D01*
Y785326D01*
X924490Y785452D01*
X924680Y785326D01*
Y785074D01*
X924490Y784948D01*
G01X932065Y792775D02*
X931308Y792523D01*
X930740Y791891D01*
X930361Y791134D01*
X930077Y790124D01*
X929982Y788987D01*
X930077Y787851D01*
X930361Y786841D01*
X930740Y786084D01*
X931308Y785452D01*
X932065Y785200D01*
X932823Y785452D01*
X933391Y786084D01*
X933770Y786841D01*
X934054Y787851D01*
X934149Y788987D01*
X934054Y790124D01*
X933770Y791134D01*
X933391Y791891D01*
X932823Y792523D01*
X932065Y792775D01*
G01X939451Y785200D02*
X939640Y786841D01*
X939925Y788230D01*
X940303Y789493D01*
X940777Y790881D01*
X941534Y792775D01*
X937747D01*
G01X945132Y786336D02*
X945700Y785705D01*
X946363Y785326D01*
X947215Y785200D01*
X948068Y785452D01*
X948730Y785957D01*
X949204Y786841D01*
X949299Y787851D01*
X949109Y788861D01*
X948636Y789493D01*
X947973Y789997D01*
X947310Y790124D01*
X946647Y789997D01*
X945795Y789493D01*
X946079Y792775D01*
X948636D01*
G01X953086Y784948D02*
X956495Y792775D01*
G01X961135Y787725D02*
X963596D01*
G01X969940Y792775D02*
X969183Y792523D01*
X968615Y791891D01*
X968236Y791134D01*
X967952Y790124D01*
X967857Y788987D01*
X967952Y787851D01*
X968236Y786841D01*
X968615Y786084D01*
X969183Y785452D01*
X969940Y785200D01*
X970698Y785452D01*
X971266Y786084D01*
X971645Y786841D01*
X971929Y787851D01*
X972024Y788987D01*
X971929Y790124D01*
X971645Y791134D01*
X971266Y791891D01*
X970698Y792523D01*
X969940Y792775D01*
G01X974675Y785200D02*
Y790250D01*
G01Y788861D02*
X974959Y789493D01*
X975432Y789997D01*
X976095Y790250D01*
X976758Y789997D01*
X977231Y789493D01*
X977515Y788861D01*
Y785200D01*
G01Y788861D02*
X977800Y789493D01*
X978273Y789997D01*
X978936Y790250D01*
X979599Y789997D01*
X980072Y789493D01*
X980356Y788735D01*
Y785200D01*
G01X982250D02*
Y790250D01*
G01Y788861D02*
X982534Y789493D01*
X983007Y789997D01*
X983670Y790250D01*
X984333Y789997D01*
X984806Y789493D01*
X985090Y788861D01*
Y785200D01*
G01Y788861D02*
X985375Y789493D01*
X985848Y789997D01*
X986511Y790250D01*
X987174Y789997D01*
X987647Y789493D01*
X987931Y788735D01*
Y785200D01*
G01X924799Y763025D02*
X927071D01*
G01X925840Y764666D02*
Y761384D01*
G01X931711Y760248D02*
X935120Y768075D01*
G01X939760Y763025D02*
X942221D01*
G01X946482Y761636D02*
X947050Y761005D01*
X947713Y760626D01*
X948565Y760500D01*
X949418Y760752D01*
X950080Y761257D01*
X950554Y762141D01*
X950649Y763151D01*
X950459Y764161D01*
X949986Y764793D01*
X949323Y765297D01*
X948660Y765424D01*
X947997Y765297D01*
X947145Y764793D01*
X947429Y768075D01*
X949986D01*
G01X953300Y760500D02*
Y765550D01*
G01Y764161D02*
X953584Y764793D01*
X954057Y765297D01*
X954720Y765550D01*
X955383Y765297D01*
X955856Y764793D01*
X956140Y764161D01*
Y760500D01*
G01Y764161D02*
X956425Y764793D01*
X956898Y765297D01*
X957561Y765550D01*
X958224Y765297D01*
X958697Y764793D01*
X958981Y764035D01*
Y760500D01*
G01X963715Y765550D02*
Y760500D01*
G01Y767570D02*
X963526Y767696D01*
Y767949D01*
X963715Y768075D01*
X963905Y767949D01*
Y767696D01*
X963715Y767570D01*
G01X971290Y760500D02*
Y768075D01*
G01X924799Y775525D02*
X927071D01*
G01X925840Y777166D02*
Y773884D01*
G01X931711Y772748D02*
X935120Y780575D01*
G01X939760Y775525D02*
X942221D01*
G01X948565Y780575D02*
X947808Y780323D01*
X947240Y779691D01*
X946861Y778934D01*
X946577Y777924D01*
X946482Y776787D01*
X946577Y775651D01*
X946861Y774641D01*
X947240Y773884D01*
X947808Y773252D01*
X948565Y773000D01*
X949323Y773252D01*
X949891Y773884D01*
X950270Y774641D01*
X950554Y775651D01*
X950649Y776787D01*
X950554Y777924D01*
X950270Y778934D01*
X949891Y779691D01*
X949323Y780323D01*
X948565Y780575D01*
G01X956140Y772748D02*
X955951Y772874D01*
Y773126D01*
X956140Y773252D01*
X956330Y773126D01*
Y772874D01*
X956140Y772748D01*
G01X963715Y780575D02*
X962958Y780323D01*
X962390Y779691D01*
X962011Y778934D01*
X961727Y777924D01*
X961632Y776787D01*
X961727Y775651D01*
X962011Y774641D01*
X962390Y773884D01*
X962958Y773252D01*
X963715Y773000D01*
X964473Y773252D01*
X965041Y773884D01*
X965420Y774641D01*
X965704Y775651D01*
X965799Y776787D01*
X965704Y777924D01*
X965420Y778934D01*
X965041Y779691D01*
X964473Y780323D01*
X963715Y780575D01*
G01X969207Y774136D02*
X969775Y773505D01*
X970438Y773126D01*
X971290Y773000D01*
X972143Y773252D01*
X972805Y773757D01*
X973279Y774641D01*
X973374Y775651D01*
X973184Y776661D01*
X972711Y777293D01*
X972048Y777797D01*
X971385Y777924D01*
X970722Y777797D01*
X969870Y777293D01*
X970154Y780575D01*
X972711D01*
G01X976025Y773000D02*
Y778050D01*
G01Y776661D02*
X976309Y777293D01*
X976782Y777797D01*
X977445Y778050D01*
X978108Y777797D01*
X978581Y777293D01*
X978865Y776661D01*
Y773000D01*
G01Y776661D02*
X979150Y777293D01*
X979623Y777797D01*
X980286Y778050D01*
X980949Y777797D01*
X981422Y777293D01*
X981706Y776535D01*
Y773000D01*
G01X983600D02*
Y778050D01*
G01Y776661D02*
X983884Y777293D01*
X984357Y777797D01*
X985020Y778050D01*
X985683Y777797D01*
X986156Y777293D01*
X986440Y776661D01*
Y773000D01*
G01Y776661D02*
X986725Y777293D01*
X987198Y777797D01*
X987861Y778050D01*
X988524Y777797D01*
X988997Y777293D01*
X989281Y776535D01*
Y773000D01*
G01X924799Y800025D02*
X927071D01*
G01X925840Y801666D02*
Y798384D01*
G01X931711Y797248D02*
X935120Y805075D01*
G01X939760Y800025D02*
X942221D01*
G01X946766Y803813D02*
X947335Y804570D01*
X947997Y804949D01*
X948755Y805075D01*
X949702Y804823D01*
X950365Y804191D01*
X950554Y803434D01*
X950459Y802676D01*
X950080Y802045D01*
X948187Y800782D01*
X947335Y799899D01*
X946766Y798636D01*
X946577Y797500D01*
X950554D01*
G01X953300D02*
Y802550D01*
G01Y801161D02*
X953584Y801793D01*
X954057Y802297D01*
X954720Y802550D01*
X955383Y802297D01*
X955856Y801793D01*
X956140Y801161D01*
Y797500D01*
G01Y801161D02*
X956425Y801793D01*
X956898Y802297D01*
X957561Y802550D01*
X958224Y802297D01*
X958697Y801793D01*
X958981Y801035D01*
Y797500D01*
G01X963715Y802550D02*
Y797500D01*
G01Y804570D02*
X963526Y804696D01*
Y804949D01*
X963715Y805075D01*
X963905Y804949D01*
Y804696D01*
X963715Y804570D01*
G01X971290Y797500D02*
Y805075D01*
G01X924799Y838025D02*
X927071D01*
G01X925840Y839666D02*
Y836384D01*
G01X931711Y835248D02*
X935120Y843075D01*
G01X939760Y838025D02*
X942221D01*
G01X946766Y841813D02*
X947335Y842570D01*
X947997Y842949D01*
X948755Y843075D01*
X949702Y842823D01*
X950365Y842191D01*
X950554Y841434D01*
X950459Y840676D01*
X950080Y840045D01*
X948187Y838782D01*
X947335Y837899D01*
X946766Y836636D01*
X946577Y835500D01*
X950554D01*
G01X953300D02*
Y840550D01*
G01Y839161D02*
X953584Y839793D01*
X954057Y840297D01*
X954720Y840550D01*
X955383Y840297D01*
X955856Y839793D01*
X956140Y839161D01*
Y835500D01*
G01Y839161D02*
X956425Y839793D01*
X956898Y840297D01*
X957561Y840550D01*
X958224Y840297D01*
X958697Y839793D01*
X958981Y839035D01*
Y835500D01*
G01X963715Y840550D02*
Y835500D01*
G01Y842570D02*
X963526Y842696D01*
Y842949D01*
X963715Y843075D01*
X963905Y842949D01*
Y842696D01*
X963715Y842570D01*
G01X971290Y835500D02*
Y843075D01*
G01X924799Y820525D02*
X927071D01*
G01X925840Y822166D02*
Y818884D01*
G01X931711Y817748D02*
X935120Y825575D01*
G01X939760Y820525D02*
X942221D01*
G01X946482Y819515D02*
X947050Y818631D01*
X947808Y818126D01*
X948660Y818000D01*
X949418Y818126D01*
X950175Y818757D01*
X950649Y819515D01*
X950743Y820272D01*
X950554Y821156D01*
X949891Y821787D01*
X949228Y822040D01*
X948376D01*
G01X949228D02*
X949796Y822419D01*
X950270Y823050D01*
X950459Y823807D01*
X950270Y824565D01*
X949796Y825196D01*
X948944Y825575D01*
X948092Y825449D01*
X947240Y824944D01*
G01X953300Y818000D02*
Y823050D01*
G01Y821661D02*
X953584Y822293D01*
X954057Y822797D01*
X954720Y823050D01*
X955383Y822797D01*
X955856Y822293D01*
X956140Y821661D01*
Y818000D01*
G01Y821661D02*
X956425Y822293D01*
X956898Y822797D01*
X957561Y823050D01*
X958224Y822797D01*
X958697Y822293D01*
X958981Y821535D01*
Y818000D01*
G01X963715Y823050D02*
Y818000D01*
G01Y825070D02*
X963526Y825196D01*
Y825449D01*
X963715Y825575D01*
X963905Y825449D01*
Y825196D01*
X963715Y825070D01*
G01X971290Y818000D02*
Y825575D01*
G01X924799Y863525D02*
X927071D01*
G01X925840Y865166D02*
Y861884D01*
G01X933415Y861000D02*
Y868575D01*
X932279Y867060D01*
G01Y861000D02*
X934552D01*
G01X939286Y860748D02*
X942695Y868575D01*
G01X947335Y863525D02*
X949796D01*
G01X954057Y862515D02*
X954625Y861631D01*
X955383Y861126D01*
X956235Y861000D01*
X956993Y861126D01*
X957750Y861757D01*
X958224Y862515D01*
X958318Y863272D01*
X958129Y864156D01*
X957466Y864787D01*
X956803Y865040D01*
X955951D01*
G01X956803D02*
X957371Y865419D01*
X957845Y866050D01*
X958034Y866807D01*
X957845Y867565D01*
X957371Y868196D01*
X956519Y868575D01*
X955667Y868449D01*
X954815Y867944D01*
G01X960875Y861000D02*
Y866050D01*
G01Y864661D02*
X961159Y865293D01*
X961632Y865797D01*
X962295Y866050D01*
X962958Y865797D01*
X963431Y865293D01*
X963715Y864661D01*
Y861000D01*
G01Y864661D02*
X964000Y865293D01*
X964473Y865797D01*
X965136Y866050D01*
X965799Y865797D01*
X966272Y865293D01*
X966556Y864535D01*
Y861000D01*
G01X971290Y866050D02*
Y861000D01*
G01Y868070D02*
X971101Y868196D01*
Y868449D01*
X971290Y868575D01*
X971480Y868449D01*
Y868196D01*
X971290Y868070D01*
G01X978865Y861000D02*
Y868575D01*
G01X924799Y875525D02*
X927071D01*
G01X925840Y877166D02*
Y873884D01*
G01X931616Y879313D02*
X932185Y880070D01*
X932847Y880449D01*
X933605Y880575D01*
X934552Y880323D01*
X935215Y879691D01*
X935404Y878934D01*
X935309Y878176D01*
X934930Y877545D01*
X933037Y876282D01*
X932185Y875399D01*
X931616Y874136D01*
X931427Y873000D01*
X935404D01*
G01X939286Y872748D02*
X942695Y880575D01*
G01X947335Y875525D02*
X949796D01*
G01X957277Y873000D02*
Y880575D01*
X953773Y875146D01*
X958508D01*
G01X960875Y873000D02*
Y878050D01*
G01Y876661D02*
X961159Y877293D01*
X961632Y877797D01*
X962295Y878050D01*
X962958Y877797D01*
X963431Y877293D01*
X963715Y876661D01*
Y873000D01*
G01Y876661D02*
X964000Y877293D01*
X964473Y877797D01*
X965136Y878050D01*
X965799Y877797D01*
X966272Y877293D01*
X966556Y876535D01*
Y873000D01*
G01X971290Y878050D02*
Y873000D01*
G01Y880070D02*
X971101Y880196D01*
Y880449D01*
X971290Y880575D01*
X971480Y880449D01*
Y880196D01*
X971290Y880070D01*
G01X978865Y873000D02*
Y880575D01*
G01X919840Y908575D02*
Y901000D01*
G01X917663Y908575D02*
X922018D01*
G01X927415Y901000D02*
X926847Y901126D01*
X926279Y901631D01*
X925900Y902515D01*
X925711Y903525D01*
X925900Y904535D01*
X926279Y905419D01*
X926847Y905924D01*
X927415Y906050D01*
X927984Y905924D01*
X928552Y905419D01*
X928930Y904535D01*
X929025Y903525D01*
X928930Y902515D01*
X928552Y901631D01*
X927984Y901126D01*
X927415Y901000D01*
G01X934990D02*
Y908575D01*
G01X941145Y904409D02*
X944175D01*
X943891Y905293D01*
X943418Y905797D01*
X942755Y906050D01*
X942092Y905924D01*
X941524Y905545D01*
X941145Y904661D01*
X940956Y903904D01*
Y903146D01*
X941145Y902389D01*
X941619Y901631D01*
X942187Y901126D01*
X942850Y901000D01*
X943512Y901252D01*
X944175Y902010D01*
G01X948815Y901000D02*
Y906050D01*
G01Y905040D02*
X949288Y905545D01*
X949762Y905924D01*
X950425Y906050D01*
X950898Y905924D01*
X951466Y905545D01*
G01X959420Y901000D02*
Y906050D01*
G01Y905166D02*
X959041Y905671D01*
X958473Y905924D01*
X957810Y906050D01*
X957147Y905797D01*
X956579Y905293D01*
X956200Y904535D01*
X956011Y903525D01*
X956200Y902515D01*
X956579Y901757D01*
X957147Y901252D01*
X957810Y901000D01*
X958473Y901126D01*
X959041Y901505D01*
X959420Y902010D01*
G01X963681Y901000D02*
Y906050D01*
G01Y904787D02*
X964060Y905419D01*
X964628Y905924D01*
X965385Y906050D01*
X966048Y905924D01*
X966616Y905419D01*
X966900Y904535D01*
Y901000D01*
G01X974380Y905419D02*
X973718Y905924D01*
X973150Y906050D01*
X972392Y905797D01*
X971824Y905293D01*
X971445Y904409D01*
X971350Y903525D01*
X971445Y902641D01*
X971824Y901884D01*
X972392Y901252D01*
X973150Y901000D01*
X973812Y901252D01*
X974380Y901757D01*
G01X979020Y904409D02*
X982050D01*
X981766Y905293D01*
X981293Y905797D01*
X980630Y906050D01*
X979967Y905924D01*
X979399Y905545D01*
X979020Y904661D01*
X978831Y903904D01*
Y903146D01*
X979020Y902389D01*
X979494Y901631D01*
X980062Y901126D01*
X980725Y901000D01*
X981387Y901252D01*
X982050Y902010D01*
G01X924799Y888025D02*
X927071D01*
G01X925840Y889666D02*
Y886384D01*
G01X931711Y885248D02*
X935120Y893075D01*
G01X939760Y888025D02*
X942221D01*
G01X946482Y887015D02*
X947050Y886131D01*
X947808Y885626D01*
X948660Y885500D01*
X949418Y885626D01*
X950175Y886257D01*
X950649Y887015D01*
X950743Y887772D01*
X950554Y888656D01*
X949891Y889287D01*
X949228Y889540D01*
X948376D01*
G01X949228D02*
X949796Y889919D01*
X950270Y890550D01*
X950459Y891307D01*
X950270Y892065D01*
X949796Y892696D01*
X948944Y893075D01*
X948092Y892949D01*
X947240Y892444D01*
G01X953300Y885500D02*
Y890550D01*
G01Y889161D02*
X953584Y889793D01*
X954057Y890297D01*
X954720Y890550D01*
X955383Y890297D01*
X955856Y889793D01*
X956140Y889161D01*
Y885500D01*
G01Y889161D02*
X956425Y889793D01*
X956898Y890297D01*
X957561Y890550D01*
X958224Y890297D01*
X958697Y889793D01*
X958981Y889035D01*
Y885500D01*
G01X963715Y890550D02*
Y885500D01*
G01Y892570D02*
X963526Y892696D01*
Y892949D01*
X963715Y893075D01*
X963905Y892949D01*
Y892696D01*
X963715Y892570D01*
G01X971290Y885500D02*
Y893075D01*
G01X-312900Y1474400D02*
Y605600D01*
X1228000D01*
Y1474400D01*
X-312900D01*
G01Y1056000D02*
X1228000D01*
G01X-127400Y842800D02*
Y864000D01*
X-127500Y864100D01*
X-131900Y859700D01*
G01X-127200Y863900D02*
Y863800D01*
X-123100Y859700D01*
G01X-126400Y903500D02*
X-126300D01*
X-123200Y906600D01*
G01X-126400Y903900D02*
X-126000D01*
G01X-126300Y923800D02*
Y904000D01*
X-126600Y903700D01*
X-129600Y906700D01*
G01X-89400Y864000D02*
X-149200D01*
X-149300Y864100D01*
G01X-89500Y903500D02*
X-149400D01*
G01X-130827Y1308797D02*
X-130817Y1296797D01*
G01X-130827Y1308797D02*
X-106806Y1284817D01*
X-106800Y1245500D01*
G01X-130827Y1308797D02*
X-118827Y1308807D01*
G01X-83000Y805400D02*
Y805200D01*
X-80500Y802700D01*
G01X-67700Y805300D02*
X-82900D01*
X-83000Y805400D01*
X-80400Y808000D01*
G01X-89300Y805500D02*
Y805200D01*
X-91200Y803300D01*
G01X-113900Y805300D02*
X-89300D01*
X-89100Y805500D01*
X-91500Y807900D01*
G01X-83100Y848100D02*
Y799100D01*
X-83200Y799000D01*
G01X-89100Y847900D02*
Y798700D01*
X-89200Y798600D01*
G01X-101400Y778500D02*
X-62500D01*
X-62200Y778800D01*
X-64800Y781400D01*
G01X-89100Y922600D02*
Y994600D01*
G01X-88800Y977400D02*
Y977300D01*
X-87000Y975500D01*
G01X-75300Y977400D02*
X-88700D01*
X-88900Y977600D01*
X-86800Y979700D01*
G01X-73380Y1289970D02*
X-31380D01*
G01X-73380D02*
X-65380Y1281970D01*
G01X-73380Y1289970D02*
X-65380Y1297970D01*
G01X-84920Y1316540D02*
X-60920Y1340540D01*
X-28920D01*
G01X-84920Y1316540D02*
Y1328540D01*
G01Y1316540D02*
X-72920D01*
G01X-37100Y778900D02*
Y778800D01*
X-33900Y775600D01*
G01X-5900Y778800D02*
X-37000D01*
X-37200Y779000D01*
X-34200Y782000D01*
G01X-62300Y778500D02*
X-62500D01*
X-65100Y775900D01*
G01X-37200Y811400D02*
Y763400D01*
G01X-62200Y810900D02*
Y763300D01*
G01X-37200Y810900D02*
X57200D01*
X57800Y810300D01*
G01X-38200Y957100D02*
X51100D01*
X51600Y957600D01*
G01X-31000Y977600D02*
X-10100D01*
X-9900Y977800D01*
X-12700Y980600D01*
X-12800D01*
G01X15800Y811400D02*
X16000D01*
X19600Y815000D01*
G01X15700Y811300D02*
X15200D01*
X11300Y815200D01*
G01X15600Y865200D02*
Y811500D01*
X15000Y810900D01*
G01X14500Y956500D02*
Y905300D01*
X15000Y904800D01*
G01X14500Y956900D02*
X17700Y953700D01*
G01X14400Y957000D02*
X11000Y953600D01*
G01X-10000Y919500D02*
Y992000D01*
X-9900Y992100D01*
G01X-10000Y977700D02*
Y977600D01*
X-12600Y975000D01*
G01X330300Y1474500D02*
Y605600D01*
G01X354000Y733000D02*
X1007000D01*
Y913000D01*
X354000D01*
Y733000D01*
G01X1007000Y745500D02*
X354000D01*
G01X382000Y733000D02*
Y758000D01*
G01Y733000D02*
X496000D01*
Y896000D01*
G01X354000Y770500D02*
Y758000D01*
X382000D01*
Y770500D01*
G01X354000Y795500D02*
Y783000D01*
X382000D01*
Y795500D01*
G01X354000Y783000D02*
Y770500D01*
X382000D01*
Y783000D01*
G01X354000Y808000D02*
Y795500D01*
X382000D01*
Y808000D01*
G01X354000Y820500D02*
Y808000D01*
X382000D01*
Y820500D01*
G01X354000Y845500D02*
Y833000D01*
X382000D01*
Y845500D01*
G01X354000Y870500D02*
Y858000D01*
X382000D01*
Y870500D01*
G01X381500Y873500D02*
X382000D01*
Y817000D01*
G01X354000Y883000D02*
Y870500D01*
X382000D01*
Y883000D01*
G01X354000Y895500D02*
Y883000D01*
X382000D01*
Y895500D01*
G01X1007000D02*
X354000D01*
G01X363000Y913000D02*
X1007000D01*
Y895500D01*
X354000D01*
Y913000D01*
X363000D01*
G01X382000Y895500D02*
Y913000D01*
G01Y883000D02*
X496000D01*
Y895500D01*
G01X1007000Y758000D02*
X496000D01*
G01X1007000Y770500D02*
X496000D01*
G01Y783000D02*
X1007000D01*
Y795500D01*
G01D02*
X496000D01*
G01X1007000Y808000D02*
X496000D01*
G01X1007000Y833000D02*
X496000D01*
G01X1007000Y858000D02*
X496000D01*
G01X1007000Y870500D02*
X496000D01*
G01Y895500D02*
Y913000D01*
G01X1007000Y883000D02*
X496000D01*
G01X905500Y733000D02*
Y913000D01*
G01X915500Y758000D02*
X1007000D01*
Y770500D01*
G01X915500D02*
X1007000D01*
Y783000D01*
G01X915500Y795500D02*
X1007000D01*
Y808000D01*
G01X915500D02*
X1007000D01*
Y833000D01*
G01X915500D02*
X1007000D01*
Y870500D01*
G01X915500Y858000D02*
X1007000D01*
Y870500D01*
G01X915500D02*
X1007000D01*
Y883000D01*
G01X915500D02*
X1007000D01*
Y895500D01*
G01X988200Y1056000D02*
Y1056100D01*
M02*
